FILE_TYPE = MACRO_DRAWING;
SET COLOR_WIRE YELLOW;
SET COLOR_PROP ORANGE;
SET COLOR_DOT WHITE;
SET COLOR_ARC YELLOW;
SET COLOR_BODY GREEN;
SET COLOR_NOTE PURPLE;
SET PROP_DISPLAY VALUE;
SET PAGE_NUMBER P299;
FORCEADD OFFPAGE..4
R 2
(-3250 -600);
FORCEPROP 2 LAST $XR0 118 
J 0
(-3532 -600);
DISPLAY 0.638298 (-3532 -600);
PAINT MONO (-3532 -600);
FORCEPROP 2 LAST CDS_LIB standard
J 0
(-3250 -600);
DISPLAY INVISIBLE (-3250 -600);
FORCEPROP 1 LAST OFFPAGE TRUE
J 2
(-3575 -725);
DISPLAY 0.872340 (-3575 -725);
PAINT GREEN (-3575 -725);
DISPLAY INVISIBLE (-3575 -725);
FORCEPROP 1 LAST COMMENT_BODY TRUE
J 2
(-3225 -700);
DISPLAY 0.872340 (-3225 -700);
PAINT GREEN (-3225 -700);
DISPLAY INVISIBLE (-3225 -700);
FORCEPROP 2 LAST PATH I1
J 0
(-3525 -550);
DISPLAY 1.021277 (-3525 -550);
DISPLAY INVISIBLE (-3525 -550);
FORCEADD UNIVERSAL_POWER..1
(-2925 1500);
FORCEPROP 3 LASTPIN (-2925 1450) SIG_NAME P3V3_AUX\g
J 0
(-2915 1460);
DISPLAY 0.659574 (-2915 1460);
PAINT MONO (-2915 1460);
DISPLAY INVISIBLE (-2915 1460);
FORCEPROP 1 LAST HDL_POWER P3V3_AUX
J 1
(-2925 1550);
DISPLAY 0.872340 (-2925 1550);
PAINT GREEN (-2925 1550);
FORCEPROP 2 LAST CDS_LIB pure_quanta_power
J 0
(-2925 1500);
PAINT MONO (-2925 1500);
DISPLAY INVISIBLE (-2925 1500);
FORCEPROP 1 LAST PATH I10
J 0
(-2875 1525);
DISPLAY 0.872340 (-2875 1525);
PAINT AQUA (-2875 1525);
DISPLAY INVISIBLE (-2875 1525);
FORCEADD UNIVERSAL_GND..1
(-2950 1950);
FORCEPROP 3 LASTPIN (-2950 2000) SIG_NAME GND\g
J 0
(-2940 2010);
DISPLAY 0.659574 (-2940 2010);
PAINT MONO (-2940 2010);
DISPLAY INVISIBLE (-2940 2010);
FORCEPROP 2 LAST CDS_LIB pure_quanta_power
J 0
(-2950 1950);
DISPLAY INVISIBLE (-2950 1950);
FORCEPROP 1 LAST HDL_POWER GND
J 1
(-2925 1875);
DISPLAY 0.872340 (-2925 1875);
PAINT GREEN (-2925 1875);
DISPLAY INVISIBLE (-2925 1875);
FORCEPROP 1 LAST PATH I11
J 0
(-2875 1950);
DISPLAY 0.872340 (-2875 1950);
PAINT AQUA (-2875 1950);
DISPLAY INVISIBLE (-2875 1950);
FORCEADD OFFPAGE..4
R 2
(-3175 2325);
FORCEPROP 2 LAST $XR0 120 
J 0
(-3427 2325);
DISPLAY 0.638298 (-3427 2325);
PAINT MONO (-3427 2325);
FORCEPROP 2 LAST CDS_LIB standard
J 0
(-3175 2325);
DISPLAY INVISIBLE (-3175 2325);
FORCEPROP 1 LAST OFFPAGE TRUE
J 2
(-3500 2200);
DISPLAY 0.872340 (-3500 2200);
PAINT GREEN (-3500 2200);
DISPLAY INVISIBLE (-3500 2200);
FORCEPROP 1 LAST COMMENT_BODY TRUE
J 2
(-3150 2225);
DISPLAY 0.872340 (-3150 2225);
PAINT GREEN (-3150 2225);
DISPLAY INVISIBLE (-3150 2225);
FORCEPROP 2 LAST PATH I12
J 0
(-3125 2400);
DISPLAY 1.021277 (-3125 2400);
DISPLAY INVISIBLE (-3125 2400);
FORCEADD Q_CAP..1
(100 1300);
FORCEPROP 1 LAST LOCATION C1975
J 0
(150 1400);
DISPLAY 0.638298 (150 1400);
FORCEPROP 2 LAST $SEC 1
J 0
(150 1500);
DISPLAY 0.680851 (150 1500);
PAINT MONO (150 1500);
DISPLAY INVISIBLE (150 1500);
FORCEPROP 2 LAST CDS_SEC 1
J 0
(150 1500);
DISPLAY 1.021277 (150 1500);
DISPLAY INVISIBLE (150 1500);
FORCEPROP 1 LASTPIN (100 1400) $PN 1
J 0
(110 1380);
DISPLAY 0.787234 (110 1380);
PAINT MONO (110 1380);
FORCEPROP 1 LASTPIN (100 1200) $PN 2
J 0
(110 1180);
DISPLAY 0.787234 (110 1180);
PAINT MONO (110 1180);
FORCEPROP 1 LAST VALUE 0.1UF
J 0
(150 1350);
DISPLAY 0.638298 (150 1350);
FORCEPROP 1 LAST VOLTAGE 25V
J 0
(150 1300);
DISPLAY 0.638298 (150 1300);
FORCEPROP 1 LAST TOLERANCE 10%
J 0
(150 1250);
DISPLAY 0.638298 (150 1250);
FORCEPROP 1 LAST MATERIAL X7R
J 0
(150 1200);
DISPLAY 0.638298 (150 1200);
PAINT RED (150 1200);
FORCEPROP 1 LAST PACK_TYPE 0402
J 0
(150 1100);
DISPLAY 0.638298 (150 1100);
FORCEPROP 2 LAST CDS_LIB pure_quanta
J 0
(100 1300);
DISPLAY INVISIBLE (100 1300);
FORCEPROP 1 LAST PATH I129
J 0
(150 1450);
DISPLAY 0.978723 (150 1450);
PAINT WHITE (150 1450);
DISPLAY INVISIBLE (150 1450);
FORCEPROP 1 LAST PART_NUMBER CH4104K1B00
J 0
(150 1150);
DISPLAY 0.638298 (150 1150);
DISPLAY INVISIBLE (150 1150);
FORCEADD Q_RES..2
(-2975 2600);
FORCEPROP 1 LAST LOCATION R3429
J 0
(-2930 2725);
DISPLAY 0.978723 (-2930 2725);
FORCEPROP 0 LAST $SEC 1
J 0
(-2925 2775);
DISPLAY 0.680851 (-2925 2775);
PAINT MONO (-2925 2775);
DISPLAY INVISIBLE (-2925 2775);
FORCEPROP 0 LAST CDS_SEC 1
J 0
(-2925 2775);
DISPLAY 1.021277 (-2925 2775);
DISPLAY INVISIBLE (-2925 2775);
FORCEPROP 1 LASTPIN (-2975 2700) $PN 1
J 0
(-2970 2662);
DISPLAY 0.787234 (-2970 2662);
PAINT MONO (-2970 2662);
FORCEPROP 1 LASTPIN (-2975 2500) $PN 2
J 0
(-2970 2510);
DISPLAY 0.787234 (-2970 2510);
PAINT MONO (-2970 2510);
FORCEPROP 1 LAST WATTAGE 1/16W
J 0
(-2935 2575);
DISPLAY 0.510638 (-2935 2575);
FORCEPROP 1 LAST TOLERANCE 1%
J 0
(-2930 2625);
DISPLAY 0.510638 (-2930 2625);
FORCEPROP 1 LAST VALUE 100K
J 0
(-2930 2675);
DISPLAY 0.510638 (-2930 2675);
FORCEPROP 1 LAST PACK_TYPE 0402LF
J 0
(-2935 2425);
DISPLAY 0.510638 (-2935 2425);
FORCEPROP 1 LAST MATERIAL EMPTY
J 0
(-2935 2525);
DISPLAY 0.510638 (-2935 2525);
PAINT RED (-2935 2525);
FORCEPROP 2 LAST CDS_LIB pure_quanta
J 0
(-2975 2600);
DISPLAY INVISIBLE (-2975 2600);
FORCEPROP 1 LAST PATH I130
J 0
(-2925 2775);
DISPLAY 0.978723 (-2925 2775);
PAINT WHITE (-2925 2775);
DISPLAY INVISIBLE (-2925 2775);
FORCEPROP 1 LAST PART_NUMBER CS41002FB09
J 0
(-2935 2475);
DISPLAY 0.510638 (-2935 2475);
DISPLAY INVISIBLE (-2935 2475);
FORCEADD Q_RES..2
(-2950 2125);
FORCEPROP 1 LAST LOCATION R3463
J 0
(-2905 2250);
DISPLAY 0.978723 (-2905 2250);
FORCEPROP 0 LAST $SEC 1
J 0
(-2900 2300);
DISPLAY 0.680851 (-2900 2300);
PAINT MONO (-2900 2300);
DISPLAY INVISIBLE (-2900 2300);
FORCEPROP 0 LAST CDS_SEC 1
J 0
(-2900 2300);
DISPLAY 1.021277 (-2900 2300);
DISPLAY INVISIBLE (-2900 2300);
FORCEPROP 1 LASTPIN (-2950 2225) $PN 1
J 0
(-2945 2187);
DISPLAY 0.787234 (-2945 2187);
PAINT MONO (-2945 2187);
FORCEPROP 1 LASTPIN (-2950 2025) $PN 2
J 0
(-2945 2035);
DISPLAY 0.787234 (-2945 2035);
PAINT MONO (-2945 2035);
FORCEPROP 1 LAST WATTAGE 1/16W
J 0
(-2910 2100);
DISPLAY 0.787234 (-2910 2100);
FORCEPROP 1 LAST PACK_TYPE 0402LF
J 0
(-2910 1950);
DISPLAY 0.787234 (-2910 1950);
FORCEPROP 1 LAST MATERIAL CHIP
J 0
(-2910 2050);
DISPLAY 0.787234 (-2910 2050);
FORCEPROP 1 LAST VALUE 54.9K
J 0
(-2905 2200);
DISPLAY 0.787234 (-2905 2200);
FORCEPROP 1 LAST TOLERANCE 1%
J 0
(-2905 2150);
DISPLAY 0.787234 (-2905 2150);
FORCEPROP 2 LAST CDS_LIB pure_quanta
J 0
(-2950 2125);
DISPLAY INVISIBLE (-2950 2125);
FORCEPROP 1 LAST PATH I131
J 0
(-2900 2300);
DISPLAY 0.978723 (-2900 2300);
PAINT WHITE (-2900 2300);
DISPLAY INVISIBLE (-2900 2300);
FORCEPROP 1 LAST PART_NUMBER CS35492FB03
J 0
(-2910 2000);
DISPLAY 0.787234 (-2910 2000);
DISPLAY INVISIBLE (-2910 2000);
FORCEADD Q_RES..2
(-2925 1250);
FORCEPROP 1 LAST LOCATION R3465
J 0
(-2880 1375);
DISPLAY 0.978723 (-2880 1375);
FORCEPROP 0 LAST $SEC 1
J 0
(-2875 1425);
DISPLAY 0.680851 (-2875 1425);
PAINT MONO (-2875 1425);
DISPLAY INVISIBLE (-2875 1425);
FORCEPROP 0 LAST CDS_SEC 1
J 0
(-2875 1425);
DISPLAY 1.021277 (-2875 1425);
DISPLAY INVISIBLE (-2875 1425);
FORCEPROP 1 LASTPIN (-2925 1350) $PN 1
J 0
(-2920 1312);
DISPLAY 0.787234 (-2920 1312);
PAINT MONO (-2920 1312);
FORCEPROP 1 LASTPIN (-2925 1150) $PN 2
J 0
(-2920 1160);
DISPLAY 0.787234 (-2920 1160);
PAINT MONO (-2920 1160);
FORCEPROP 1 LAST MATERIAL CHIP
J 0
(-2885 1175);
DISPLAY 0.510638 (-2885 1175);
FORCEPROP 1 LAST VALUE 10K
J 0
(-2880 1325);
DISPLAY 0.510638 (-2880 1325);
FORCEPROP 1 LAST TOLERANCE 1%
J 0
(-2880 1275);
DISPLAY 0.510638 (-2880 1275);
FORCEPROP 1 LAST PACK_TYPE 0402LF
J 0
(-2885 1075);
DISPLAY 0.510638 (-2885 1075);
FORCEPROP 1 LAST WATTAGE 1/16W
J 0
(-2885 1225);
DISPLAY 0.510638 (-2885 1225);
FORCEPROP 2 LAST CDS_LIB pure_quanta
J 0
(-2925 1250);
DISPLAY INVISIBLE (-2925 1250);
FORCEPROP 1 LAST PATH I132
J 0
(-2875 1425);
DISPLAY 0.978723 (-2875 1425);
PAINT WHITE (-2875 1425);
DISPLAY INVISIBLE (-2875 1425);
FORCEPROP 1 LAST PART_NUMBER CS31002FB08
J 0
(-2885 1125);
DISPLAY 0.510638 (-2885 1125);
DISPLAY INVISIBLE (-2885 1125);
FORCEADD Q_RES..2
(-2900 775);
FORCEPROP 1 LAST LOCATION R3431
J 0
(-2855 900);
DISPLAY 0.978723 (-2855 900);
FORCEPROP 0 LAST $SEC 1
J 0
(-2850 950);
DISPLAY 0.680851 (-2850 950);
PAINT MONO (-2850 950);
DISPLAY INVISIBLE (-2850 950);
FORCEPROP 0 LAST CDS_SEC 1
J 0
(-2850 950);
DISPLAY 1.021277 (-2850 950);
DISPLAY INVISIBLE (-2850 950);
FORCEPROP 1 LASTPIN (-2900 875) $PN 1
J 0
(-2895 837);
DISPLAY 0.787234 (-2895 837);
PAINT MONO (-2895 837);
FORCEPROP 1 LASTPIN (-2900 675) $PN 2
J 0
(-2895 685);
DISPLAY 0.787234 (-2895 685);
PAINT MONO (-2895 685);
FORCEPROP 1 LAST PACK_TYPE 0402LF
J 0
(-2860 600);
DISPLAY 0.510638 (-2860 600);
FORCEPROP 1 LAST WATTAGE 1/16W
J 0
(-2860 750);
DISPLAY 0.510638 (-2860 750);
FORCEPROP 1 LAST MATERIAL EMPTY
J 0
(-2860 700);
DISPLAY 0.510638 (-2860 700);
PAINT RED (-2860 700);
FORCEPROP 1 LAST VALUE 100K
J 0
(-2855 850);
DISPLAY 0.510638 (-2855 850);
FORCEPROP 1 LAST TOLERANCE 1%
J 0
(-2855 800);
DISPLAY 0.510638 (-2855 800);
FORCEPROP 2 LAST CDS_LIB pure_quanta
J 0
(-2900 775);
DISPLAY INVISIBLE (-2900 775);
FORCEPROP 1 LAST PATH I133
J 0
(-2850 950);
DISPLAY 0.978723 (-2850 950);
PAINT WHITE (-2850 950);
DISPLAY INVISIBLE (-2850 950);
FORCEPROP 1 LAST PART_NUMBER CS41002FB09
J 0
(-2860 650);
DISPLAY 0.510638 (-2860 650);
DISPLAY INVISIBLE (-2860 650);
FORCEADD Q_RES..2
(-2975 -375);
FORCEPROP 1 LAST LOCATION R3464
J 0
(-2930 -250);
DISPLAY 0.978723 (-2930 -250);
FORCEPROP 0 LAST $SEC 1
J 0
(-2925 -200);
DISPLAY 0.680851 (-2925 -200);
PAINT MONO (-2925 -200);
DISPLAY INVISIBLE (-2925 -200);
FORCEPROP 0 LAST CDS_SEC 1
J 0
(-2925 -200);
DISPLAY 1.021277 (-2925 -200);
DISPLAY INVISIBLE (-2925 -200);
FORCEPROP 1 LASTPIN (-2975 -275) $PN 1
J 0
(-2970 -313);
DISPLAY 0.787234 (-2970 -313);
PAINT MONO (-2970 -313);
FORCEPROP 1 LASTPIN (-2975 -475) $PN 2
J 0
(-2970 -465);
DISPLAY 0.787234 (-2970 -465);
PAINT MONO (-2970 -465);
FORCEPROP 1 LAST PACK_TYPE 0402LF
J 0
(-2935 -550);
DISPLAY 0.787234 (-2935 -550);
FORCEPROP 1 LAST WATTAGE 1/16W
J 0
(-2935 -400);
DISPLAY 0.787234 (-2935 -400);
FORCEPROP 1 LAST TOLERANCE 1%
J 0
(-2930 -350);
DISPLAY 0.787234 (-2930 -350);
FORCEPROP 1 LAST MATERIAL CHIP
J 0
(-2935 -450);
DISPLAY 0.787234 (-2935 -450);
FORCEPROP 1 LAST VALUE 54.9K
J 0
(-2930 -300);
DISPLAY 0.787234 (-2930 -300);
FORCEPROP 2 LAST CDS_LIB pure_quanta
J 0
(-2975 -375);
DISPLAY INVISIBLE (-2975 -375);
FORCEPROP 1 LAST PATH I134
J 0
(-2925 -200);
DISPLAY 0.978723 (-2925 -200);
PAINT WHITE (-2925 -200);
DISPLAY INVISIBLE (-2925 -200);
FORCEPROP 1 LAST PART_NUMBER CS35492FB03
J 0
(-2935 -500);
DISPLAY 0.787234 (-2935 -500);
DISPLAY INVISIBLE (-2935 -500);
FORCEADD UNIVERSAL_POWER..1
(-2975 2850);
FORCEPROP 3 LASTPIN (-2975 2800) SIG_NAME P3V3_AUX\g
J 0
(-2965 2810);
DISPLAY 0.659574 (-2965 2810);
PAINT MONO (-2965 2810);
DISPLAY INVISIBLE (-2965 2810);
FORCEPROP 1 LAST HDL_POWER P3V3_AUX
J 1
(-2975 2900);
DISPLAY 0.872340 (-2975 2900);
PAINT GREEN (-2975 2900);
FORCEPROP 2 LAST CDS_LIB pure_quanta_power
J 0
(-2975 2850);
PAINT MONO (-2975 2850);
DISPLAY INVISIBLE (-2975 2850);
FORCEPROP 1 LAST PATH I15
J 0
(-2925 2875);
DISPLAY 0.872340 (-2925 2875);
PAINT AQUA (-2925 2875);
DISPLAY INVISIBLE (-2925 2875);
FORCEADD UNIVERSAL_POWER..1
(3875 2475);
FORCEPROP 3 LASTPIN (3875 2425) SIG_NAME P3V3_AUX\g
J 0
(3885 2435);
DISPLAY 0.659574 (3885 2435);
PAINT MONO (3885 2435);
DISPLAY INVISIBLE (3885 2435);
FORCEPROP 1 LAST HDL_POWER P3V3_AUX
J 1
(3875 2525);
DISPLAY 0.872340 (3875 2525);
PAINT GREEN (3875 2525);
FORCEPROP 2 LAST CDS_LIB pure_quanta_power
J 0
(3875 2475);
DISPLAY INVISIBLE (3875 2475);
FORCEPROP 1 LAST PATH I150
J 0
(3925 2500);
DISPLAY 0.872340 (3925 2500);
PAINT AQUA (3925 2500);
DISPLAY INVISIBLE (3925 2500);
FORCEADD OFFPAGE..2
(5050 1950);
FORCEPROP 2 LAST $XR1 246 
J 0
(5329 1950);
DISPLAY 0.638298 (5329 1950);
PAINT MONO (5329 1950);
FORCEPROP 2 LAST $XR0 81 
J 0
(5239 1950);
DISPLAY 0.638298 (5239 1950);
PAINT MONO (5239 1950);
FORCEPROP 2 LAST CDS_LIB standard
J 0
(5050 1950);
DISPLAY INVISIBLE (5050 1950);
FORCEPROP 1 LAST OFFPAGE TRUE
J 0
(5375 1825);
DISPLAY 0.872340 (5375 1825);
PAINT AQUA (5375 1825);
DISPLAY INVISIBLE (5375 1825);
FORCEPROP 1 LAST COMMENT_BODY TRUE
J 0
(5005 1855);
DISPLAY 0.872340 (5005 1855);
PAINT GREEN (5005 1855);
DISPLAY INVISIBLE (5005 1855);
FORCEPROP 2 LAST PATH I151
J 0
(5225 2025);
DISPLAY 1.021277 (5225 2025);
DISPLAY INVISIBLE (5225 2025);
FORCEADD Q_CAP..1
(4775 1550);
FORCEPROP 1 LAST LOCATION C1978
J 0
(4825 1650);
DISPLAY 0.638298 (4825 1650);
FORCEPROP 2 LAST $SEC 1
J 0
(4825 1750);
DISPLAY 0.680851 (4825 1750);
PAINT MONO (4825 1750);
DISPLAY INVISIBLE (4825 1750);
FORCEPROP 2 LAST CDS_SEC 1
J 0
(4825 1750);
DISPLAY 1.021277 (4825 1750);
DISPLAY INVISIBLE (4825 1750);
FORCEPROP 1 LASTPIN (4775 1650) $PN 1
J 0
(4785 1630);
DISPLAY 0.787234 (4785 1630);
PAINT MONO (4785 1630);
FORCEPROP 1 LASTPIN (4775 1450) $PN 2
J 0
(4785 1430);
DISPLAY 0.787234 (4785 1430);
PAINT MONO (4785 1430);
FORCEPROP 1 LAST VALUE 0.1UF
J 0
(4825 1600);
DISPLAY 0.638298 (4825 1600);
FORCEPROP 1 LAST PACK_TYPE 0402
J 0
(4825 1350);
DISPLAY 0.638298 (4825 1350);
FORCEPROP 1 LAST MATERIAL X7R
J 0
(4825 1450);
DISPLAY 0.638298 (4825 1450);
PAINT RED (4825 1450);
FORCEPROP 1 LAST VOLTAGE 25V
J 0
(4825 1550);
DISPLAY 0.638298 (4825 1550);
FORCEPROP 1 LAST TOLERANCE 10%
J 0
(4825 1500);
DISPLAY 0.638298 (4825 1500);
FORCEPROP 2 LAST CDS_LIB pure_quanta
J 0
(4775 1550);
DISPLAY INVISIBLE (4775 1550);
FORCEPROP 1 LAST PATH I152
J 0
(4825 1700);
DISPLAY 0.978723 (4825 1700);
PAINT WHITE (4825 1700);
DISPLAY INVISIBLE (4825 1700);
FORCEPROP 1 LAST PART_NUMBER CH4104K1B00
J 0
(4825 1400);
DISPLAY 0.638298 (4825 1400);
DISPLAY INVISIBLE (4825 1400);
FORCEADD UNIVERSAL_GND..1
(4775 1350);
FORCEPROP 3 LASTPIN (4775 1400) SIG_NAME GND\g
J 0
(4785 1410);
DISPLAY 0.659574 (4785 1410);
PAINT MONO (4785 1410);
DISPLAY INVISIBLE (4785 1410);
FORCEPROP 2 LAST CDS_LIB pure_quanta_power
J 0
(4775 1350);
DISPLAY INVISIBLE (4775 1350);
FORCEPROP 1 LAST HDL_POWER GND
J 1
(4800 1275);
DISPLAY 0.872340 (4800 1275);
PAINT GREEN (4800 1275);
DISPLAY INVISIBLE (4800 1275);
FORCEPROP 1 LAST PATH I153
J 0
(4850 1350);
DISPLAY 0.872340 (4850 1350);
PAINT AQUA (4850 1350);
DISPLAY INVISIBLE (4850 1350);
FORCEADD Q_RES..2
(3875 2175);
FORCEPROP 1 LAST LOCATION R3475
J 0
(3920 2300);
DISPLAY 0.978723 (3920 2300);
FORCEPROP 0 LAST $SEC 1
J 0
(3925 2350);
DISPLAY 0.680851 (3925 2350);
PAINT MONO (3925 2350);
DISPLAY INVISIBLE (3925 2350);
FORCEPROP 0 LAST CDS_SEC 1
J 0
(3925 2350);
DISPLAY 1.021277 (3925 2350);
DISPLAY INVISIBLE (3925 2350);
FORCEPROP 1 LASTPIN (3875 2275) $PN 1
J 0
(3880 2237);
DISPLAY 0.787234 (3880 2237);
PAINT MONO (3880 2237);
FORCEPROP 1 LASTPIN (3875 2075) $PN 2
J 0
(3880 2085);
DISPLAY 0.787234 (3880 2085);
PAINT MONO (3880 2085);
FORCEPROP 1 LAST WATTAGE 1/16W
J 0
(3915 2150);
DISPLAY 0.638298 (3915 2150);
FORCEPROP 1 LAST MATERIAL CHIP
J 0
(3915 2100);
DISPLAY 0.638298 (3915 2100);
FORCEPROP 1 LAST PACK_TYPE 0402LF
J 0
(3915 2050);
DISPLAY 0.638298 (3915 2050);
FORCEPROP 1 LAST VALUE 100K
J 0
(3920 2250);
DISPLAY 0.638298 (3920 2250);
FORCEPROP 1 LAST TOLERANCE 1%
J 0
(3920 2200);
DISPLAY 0.638298 (3920 2200);
FORCEPROP 2 LAST CDS_LIB pure_quanta
J 0
(3875 2175);
DISPLAY INVISIBLE (3875 2175);
FORCEPROP 1 LAST PATH I154
J 0
(3925 2350);
DISPLAY 0.978723 (3925 2350);
PAINT WHITE (3925 2350);
DISPLAY INVISIBLE (3925 2350);
FORCEPROP 1 LAST PART_NUMBER CS41002FB09
J 0
(3915 2000);
DISPLAY 0.638298 (3915 2000);
DISPLAY INVISIBLE (3915 2000);
FORCEADD UNIVERSAL_POWER..1
(2950 2225);
FORCEPROP 3 LASTPIN (2950 2175) SIG_NAME P3V3_AUX\g
J 0
(2960 2185);
DISPLAY 0.659574 (2960 2185);
PAINT MONO (2960 2185);
DISPLAY INVISIBLE (2960 2185);
FORCEPROP 1 LAST HDL_POWER P3V3_AUX
J 1
(2950 2275);
DISPLAY 0.872340 (2950 2275);
PAINT GREEN (2950 2275);
FORCEPROP 2 LAST CDS_LIB pure_quanta_power
J 0
(2950 2225);
PAINT MONO (2950 2225);
DISPLAY INVISIBLE (2950 2225);
FORCEPROP 1 LAST PATH I155
J 0
(3000 2250);
DISPLAY 0.872340 (3000 2250);
PAINT AQUA (3000 2250);
DISPLAY INVISIBLE (3000 2250);
FORCEADD UNIVERSAL_GND..1
(3875 1350);
FORCEPROP 3 LASTPIN (3875 1400) SIG_NAME GND\g
J 0
(3885 1410);
DISPLAY 0.659574 (3885 1410);
PAINT MONO (3885 1410);
DISPLAY INVISIBLE (3885 1410);
FORCEPROP 2 LAST CDS_LIB pure_quanta_power
J 0
(3875 1350);
DISPLAY INVISIBLE (3875 1350);
FORCEPROP 1 LAST HDL_POWER GND
J 1
(3900 1275);
DISPLAY 0.872340 (3900 1275);
PAINT GREEN (3900 1275);
DISPLAY INVISIBLE (3900 1275);
FORCEPROP 1 LAST PATH I156
J 0
(3950 1350);
DISPLAY 0.872340 (3950 1350);
PAINT AQUA (3950 1350);
DISPLAY INVISIBLE (3950 1350);
FORCEADD MOSFET_NCH_DUAL..2
(3825 1725);
FORCEPROP 1 LAST LOCATION Q107
J 0
(3976 1701);
DISPLAY 0.723404 (3976 1701);
PAINT GREEN (3976 1701);
FORCEPROP 0 LAST $SEC 2
J 0
(4000 1850);
DISPLAY 0.680851 (4000 1850);
PAINT MONO (4000 1850);
DISPLAY INVISIBLE (4000 1850);
FORCEPROP 0 LAST CDS_SEC 2
J 0
(4000 1850);
DISPLAY 1.021277 (4000 1850);
DISPLAY INVISIBLE (4000 1850);
FORCEPROP 0 LASTPIN (3875 1925) $PN 3
R 1
J 0
(3865 1935);
DISPLAY 0.680851 (3865 1935);
PAINT MONO (3865 1935);
FORCEPROP 0 LASTPIN (3625 1675) $PN 5
J 2
(3615 1685);
DISPLAY 0.680851 (3615 1685);
PAINT MONO (3615 1685);
FORCEPROP 0 LASTPIN (3875 1525) $PN 4
R 1
J 2
(3865 1515);
DISPLAY 0.680851 (3865 1515);
PAINT MONO (3865 1515);
FORCEPROP 2 LAST VALUE PJT138K
J 0
(4000 1750);
DISPLAY 1.021277 (4000 1750);
FORCEPROP 2 LAST PART_TYPE SMLF
J 0
(4000 1800);
DISPLAY 1.021277 (4000 1800);
FORCEPROP 1 LAST MATERIAL IC
J 0
(3976 1576);
DISPLAY 0.723404 (3976 1576);
PAINT GREEN (3976 1576);
FORCEPROP 1 LAST CDS_LMAN_SYM_OUTLINE -150,150,150,-150
J 0
(3825 1725);
DISPLAY 0.468085 (3825 1725);
PAINT GREEN (3825 1725);
DISPLAY INVISIBLE (3825 1725);
FORCEPROP 1 LAST NEEDS_NO_SIZE TRUE
J 0
(3975 1616);
DISPLAY 0.468085 (3975 1616);
PAINT GREEN (3975 1616);
DISPLAY INVISIBLE (3975 1616);
FORCEPROP 2 LAST CDS_LIB pure_quanta
J 0
(3825 1725);
DISPLAY INVISIBLE (3825 1725);
FORCEPROP 1 LAST PATH I157
J 0
(3975 1575);
DISPLAY 0.723404 (3975 1575);
PAINT GREEN (3975 1575);
DISPLAY INVISIBLE (3975 1575);
FORCEPROP 1 LAST PART_NUMBER BAM138K0003
J 0
(3976 1631);
DISPLAY 0.723404 (3976 1631);
PAINT GREEN (3976 1631);
DISPLAY INVISIBLE (3976 1631);
FORCEADD Q_RES..2
(2950 1925);
FORCEPROP 1 LAST LOCATION R3474
J 0
(2995 2050);
DISPLAY 0.638298 (2995 2050);
FORCEPROP 2 LAST $SEC 1
J 0
(3000 2150);
DISPLAY 0.680851 (3000 2150);
PAINT MONO (3000 2150);
DISPLAY INVISIBLE (3000 2150);
FORCEPROP 2 LAST CDS_SEC 1
J 0
(3000 2150);
DISPLAY 1.021277 (3000 2150);
DISPLAY INVISIBLE (3000 2150);
FORCEPROP 1 LASTPIN (2950 2025) $PN 1
J 0
(2955 1987);
DISPLAY 0.787234 (2955 1987);
FORCEPROP 1 LASTPIN (2950 1825) $PN 2
J 0
(2955 1835);
DISPLAY 0.787234 (2955 1835);
FORCEPROP 1 LAST TOLERANCE 5%
J 0
(2995 1950);
DISPLAY 0.638298 (2995 1950);
FORCEPROP 1 LAST VALUE 4.7K
J 0
(2995 2000);
DISPLAY 0.638298 (2995 2000);
FORCEPROP 1 LAST WATTAGE 1/16W
J 0
(2990 1900);
DISPLAY 0.638298 (2990 1900);
FORCEPROP 1 LAST MATERIAL CHIP
J 0
(2990 1850);
DISPLAY 0.638298 (2990 1850);
FORCEPROP 1 LAST PACK_TYPE 0402LF
J 0
(2990 1800);
DISPLAY 0.638298 (2990 1800);
FORCEPROP 2 LAST CDS_LIB pure_quanta
J 0
(2950 1925);
PAINT MONO (2950 1925);
DISPLAY INVISIBLE (2950 1925);
FORCEPROP 1 LAST PATH I158
J 0
(3000 2100);
DISPLAY 0.978723 (3000 2100);
PAINT WHITE (3000 2100);
DISPLAY INVISIBLE (3000 2100);
FORCEPROP 1 LAST PART_NUMBER CS24702JB10
J 0
(2990 1750);
DISPLAY 0.638298 (2990 1750);
DISPLAY INVISIBLE (2990 1750);
FORCEADD UNIVERSAL_GND..1
(2950 1075);
FORCEPROP 3 LASTPIN (2950 1125) SIG_NAME GND\g
J 0
(2960 1135);
DISPLAY 0.659574 (2960 1135);
PAINT MONO (2960 1135);
DISPLAY INVISIBLE (2960 1135);
FORCEPROP 2 LAST CDS_LIB pure_quanta_power
J 0
(2950 1075);
DISPLAY INVISIBLE (2950 1075);
FORCEPROP 1 LAST HDL_POWER GND
J 1
(2975 1000);
DISPLAY 0.872340 (2975 1000);
PAINT GREEN (2975 1000);
DISPLAY INVISIBLE (2975 1000);
FORCEPROP 1 LAST PATH I159
J 0
(3025 1075);
DISPLAY 0.872340 (3025 1075);
PAINT AQUA (3025 1075);
DISPLAY INVISIBLE (3025 1075);
FORCEADD UNIVERSAL_GND..1
(-2975 3325);
FORCEPROP 3 LASTPIN (-2975 3375) SIG_NAME GND\g
J 0
(-2965 3385);
DISPLAY 0.659574 (-2965 3385);
PAINT MONO (-2965 3385);
DISPLAY INVISIBLE (-2965 3385);
FORCEPROP 2 LAST CDS_LIB pure_quanta_power
J 0
(-2975 3325);
DISPLAY INVISIBLE (-2975 3325);
FORCEPROP 1 LAST HDL_POWER GND
J 1
(-2950 3250);
DISPLAY 0.872340 (-2950 3250);
PAINT GREEN (-2950 3250);
DISPLAY INVISIBLE (-2950 3250);
FORCEPROP 1 LAST PATH I16
J 0
(-2900 3325);
DISPLAY 0.872340 (-2900 3325);
PAINT AQUA (-2900 3325);
DISPLAY INVISIBLE (-2900 3325);
FORCEADD MOSFET_NCH_DUAL..1
(2900 1450);
FORCEPROP 1 LAST LOCATION Q107
J 0
(3051 1424);
DISPLAY 0.723404 (3051 1424);
PAINT GREEN (3051 1424);
FORCEPROP 0 LAST $SEC 1
J 0
(3075 1575);
DISPLAY 0.680851 (3075 1575);
PAINT MONO (3075 1575);
DISPLAY INVISIBLE (3075 1575);
FORCEPROP 2 LAST CDS_SEC 1
J 0
(3075 1575);
DISPLAY 1.021277 (3075 1575);
DISPLAY INVISIBLE (3075 1575);
FORCEPROP 0 LASTPIN (2950 1650) $PN 6
R 1
J 0
(2940 1660);
DISPLAY 0.680851 (2940 1660);
PAINT MONO (2940 1660);
FORCEPROP 0 LASTPIN (2700 1400) $PN 2
J 2
(2690 1410);
DISPLAY 0.680851 (2690 1410);
PAINT MONO (2690 1410);
FORCEPROP 0 LASTPIN (2950 1250) $PN 1
R 1
J 2
(2940 1240);
DISPLAY 0.680851 (2940 1240);
PAINT MONO (2940 1240);
FORCEPROP 1 LAST MATERIAL IC
J 0
(3051 1299);
DISPLAY 0.723404 (3051 1299);
PAINT GREEN (3051 1299);
FORCEPROP 2 LAST PART_TYPE SMLF
J 0
(3075 1525);
DISPLAY 1.021277 (3075 1525);
FORCEPROP 2 LAST VALUE PJT138K
J 0
(3075 1475);
DISPLAY 1.021277 (3075 1475);
FORCEPROP 1 LAST CDS_LMAN_SYM_OUTLINE -150,150,150,-150
J 0
(2900 1450);
DISPLAY 0.468085 (2900 1450);
PAINT GREEN (2900 1450);
DISPLAY INVISIBLE (2900 1450);
FORCEPROP 1 LAST NEEDS_NO_SIZE TRUE
J 0
(2900 1449);
DISPLAY 0.468085 (2900 1449);
PAINT GREEN (2900 1449);
DISPLAY INVISIBLE (2900 1449);
FORCEPROP 2 LAST CDS_LIB pure_quanta
J 0
(2900 1450);
DISPLAY INVISIBLE (2900 1450);
FORCEPROP 1 LAST PATH I160
J 0
(2900 1450);
DISPLAY 0.723404 (2900 1450);
PAINT GREEN (2900 1450);
DISPLAY INVISIBLE (2900 1450);
FORCEPROP 1 LAST PART_NUMBER BAM138K0003
J 0
(3051 1364);
DISPLAY 0.723404 (3051 1364);
PAINT GREEN (3051 1364);
DISPLAY INVISIBLE (3051 1364);
FORCEADD UNIVERSAL_POWER..1
(1700 1925);
FORCEPROP 3 LASTPIN (1700 1875) SIG_NAME P3V3_AUX\g
J 0
(1710 1885);
DISPLAY 0.659574 (1710 1885);
PAINT MONO (1710 1885);
DISPLAY INVISIBLE (1710 1885);
FORCEPROP 1 LAST HDL_POWER P3V3_AUX
J 1
(1700 1975);
DISPLAY 0.872340 (1700 1975);
PAINT GREEN (1700 1975);
FORCEPROP 2 LAST CDS_LIB pure_quanta_power
J 0
(1700 1925);
PAINT MONO (1700 1925);
DISPLAY INVISIBLE (1700 1925);
FORCEPROP 1 LAST PATH I161
J 0
(1750 1950);
DISPLAY 0.872340 (1750 1950);
PAINT AQUA (1750 1950);
DISPLAY INVISIBLE (1750 1950);
FORCEADD Q_RES..2
(1725 1200);
FORCEPROP 1 LAST LOCATION R3473
J 0
(1770 1325);
DISPLAY 0.978723 (1770 1325);
FORCEPROP 0 LAST $SEC 1
J 0
(1775 1375);
DISPLAY 0.680851 (1775 1375);
PAINT MONO (1775 1375);
DISPLAY INVISIBLE (1775 1375);
FORCEPROP 0 LAST CDS_SEC 1
J 0
(1775 1375);
DISPLAY 1.021277 (1775 1375);
DISPLAY INVISIBLE (1775 1375);
FORCEPROP 1 LASTPIN (1725 1300) $PN 1
J 0
(1730 1262);
DISPLAY 0.787234 (1730 1262);
PAINT MONO (1730 1262);
FORCEPROP 1 LASTPIN (1725 1100) $PN 2
J 0
(1730 1110);
DISPLAY 0.787234 (1730 1110);
PAINT MONO (1730 1110);
FORCEPROP 1 LAST PACK_TYPE 0402LF
J 0
(1765 1025);
DISPLAY 0.510638 (1765 1025);
FORCEPROP 1 LAST WATTAGE 1/16W
J 0
(1765 1175);
DISPLAY 0.510638 (1765 1175);
FORCEPROP 1 LAST MATERIAL EMPTY
J 0
(1765 1125);
DISPLAY 0.510638 (1765 1125);
PAINT RED (1765 1125);
FORCEPROP 1 LAST TOLERANCE 1%
J 0
(1770 1225);
DISPLAY 0.510638 (1770 1225);
FORCEPROP 1 LAST VALUE 100K
J 0
(1770 1275);
DISPLAY 0.510638 (1770 1275);
FORCEPROP 2 LAST CDS_LIB pure_quanta
J 0
(1725 1200);
DISPLAY INVISIBLE (1725 1200);
FORCEPROP 1 LAST PATH I163
J 0
(1775 1375);
DISPLAY 0.978723 (1775 1375);
PAINT WHITE (1775 1375);
DISPLAY INVISIBLE (1775 1375);
FORCEPROP 1 LAST PART_NUMBER CS41002FB09
J 0
(1765 1075);
DISPLAY 0.510638 (1765 1075);
DISPLAY INVISIBLE (1765 1075);
FORCEADD UNIVERSAL_GND..1
(1725 1000);
FORCEPROP 3 LASTPIN (1725 1050) SIG_NAME GND\g
J 0
(1735 1060);
DISPLAY 0.659574 (1735 1060);
PAINT MONO (1735 1060);
DISPLAY INVISIBLE (1735 1060);
FORCEPROP 2 LAST CDS_LIB pure_quanta_power
J 0
(1725 1000);
DISPLAY INVISIBLE (1725 1000);
FORCEPROP 1 LAST HDL_POWER GND
J 1
(1750 925);
DISPLAY 0.872340 (1750 925);
PAINT GREEN (1750 925);
DISPLAY INVISIBLE (1750 925);
FORCEPROP 1 LAST PATH I164
J 0
(1800 1000);
DISPLAY 0.872340 (1800 1000);
PAINT AQUA (1800 1000);
DISPLAY INVISIBLE (1800 1000);
FORCEADD OFFPAGE..4
R 2
(1425 1400);
FORCEPROP 2 LAST $XR0 121 
J 0
(1173 1400);
DISPLAY 0.638298 (1173 1400);
PAINT MONO (1173 1400);
FORCEPROP 2 LAST CDS_LIB standard
J 0
(1425 1400);
DISPLAY INVISIBLE (1425 1400);
FORCEPROP 1 LAST OFFPAGE TRUE
J 2
(1100 1275);
DISPLAY 0.872340 (1100 1275);
PAINT GREEN (1100 1275);
DISPLAY INVISIBLE (1100 1275);
FORCEPROP 1 LAST COMMENT_BODY TRUE
J 2
(1450 1300);
DISPLAY 0.872340 (1450 1300);
PAINT GREEN (1450 1300);
DISPLAY INVISIBLE (1450 1300);
FORCEPROP 2 LAST PATH I165
J 0
(1150 1450);
DISPLAY 1.021277 (1150 1450);
DISPLAY INVISIBLE (1150 1450);
FORCEADD Q_RES..2
(1700 1625);
FORCEPROP 1 LAST LOCATION R3487
J 0
(1745 1750);
DISPLAY 0.978723 (1745 1750);
FORCEPROP 0 LAST $SEC 1
J 0
(1750 1800);
DISPLAY 0.680851 (1750 1800);
PAINT MONO (1750 1800);
DISPLAY INVISIBLE (1750 1800);
FORCEPROP 0 LAST CDS_SEC 1
J 0
(1750 1800);
DISPLAY 1.021277 (1750 1800);
DISPLAY INVISIBLE (1750 1800);
FORCEPROP 1 LASTPIN (1700 1725) $PN 1
J 0
(1705 1687);
DISPLAY 0.787234 (1705 1687);
PAINT MONO (1705 1687);
FORCEPROP 1 LASTPIN (1700 1525) $PN 2
J 0
(1705 1535);
DISPLAY 0.787234 (1705 1535);
PAINT MONO (1705 1535);
FORCEPROP 1 LAST PACK_TYPE 0402LF
J 0
(1740 1450);
DISPLAY 0.510638 (1740 1450);
FORCEPROP 1 LAST VALUE 10K
J 0
(1745 1700);
DISPLAY 0.510638 (1745 1700);
FORCEPROP 1 LAST WATTAGE 1/16W
J 0
(1740 1600);
DISPLAY 0.510638 (1740 1600);
FORCEPROP 1 LAST MATERIAL CHIP
J 0
(1740 1550);
DISPLAY 0.510638 (1740 1550);
FORCEPROP 1 LAST TOLERANCE 1%
J 0
(1745 1650);
DISPLAY 0.510638 (1745 1650);
FORCEPROP 2 LAST CDS_LIB pure_quanta
J 0
(1700 1625);
DISPLAY INVISIBLE (1700 1625);
FORCEPROP 1 LAST PATH I166
J 0
(1750 1800);
DISPLAY 0.978723 (1750 1800);
PAINT WHITE (1750 1800);
DISPLAY INVISIBLE (1750 1800);
FORCEPROP 1 LAST PART_NUMBER CS31002FB08
J 0
(1740 1500);
DISPLAY 0.510638 (1740 1500);
DISPLAY INVISIBLE (1740 1500);
FORCEADD Q_RES..2
(-3000 4000);
FORCEPROP 1 LAST LOCATION R3498
J 0
(-2955 4125);
DISPLAY 0.978723 (-2955 4125);
FORCEPROP 0 LAST $SEC 1
J 0
(-2950 4175);
DISPLAY 0.680851 (-2950 4175);
PAINT MONO (-2950 4175);
DISPLAY INVISIBLE (-2950 4175);
FORCEPROP 0 LAST CDS_SEC 1
J 0
(-2950 4175);
DISPLAY 1.021277 (-2950 4175);
DISPLAY INVISIBLE (-2950 4175);
FORCEPROP 1 LASTPIN (-3000 4100) $PN 1
J 0
(-2995 4062);
DISPLAY 0.787234 (-2995 4062);
PAINT MONO (-2995 4062);
FORCEPROP 1 LASTPIN (-3000 3900) $PN 2
J 0
(-2995 3910);
DISPLAY 0.787234 (-2995 3910);
PAINT MONO (-2995 3910);
FORCEPROP 1 LAST VALUE 54.9K
J 0
(-2955 4075);
DISPLAY 0.787234 (-2955 4075);
FORCEPROP 1 LAST TOLERANCE 1%
J 0
(-2955 4025);
DISPLAY 0.787234 (-2955 4025);
FORCEPROP 1 LAST MATERIAL CHIP
J 0
(-2960 3925);
DISPLAY 0.787234 (-2960 3925);
FORCEPROP 1 LAST WATTAGE 1/16W
J 0
(-2960 3975);
DISPLAY 0.787234 (-2960 3975);
FORCEPROP 1 LAST PACK_TYPE 0402LF
J 0
(-2960 3825);
DISPLAY 0.787234 (-2960 3825);
FORCEPROP 2 LAST CDS_LIB pure_quanta
J 0
(-3000 4000);
DISPLAY INVISIBLE (-3000 4000);
FORCEPROP 1 LAST PATH I167
J 0
(-2950 4175);
DISPLAY 0.978723 (-2950 4175);
PAINT WHITE (-2950 4175);
DISPLAY INVISIBLE (-2950 4175);
FORCEPROP 1 LAST PART_NUMBER CS35492FB03
J 0
(-2960 3875);
DISPLAY 0.787234 (-2960 3875);
DISPLAY INVISIBLE (-2960 3875);
FORCEADD MOSFET_NCH_DUAL..2
(3850 0);
FORCEPROP 1 LAST LOCATION Q108
J 0
(4001 -24);
DISPLAY 0.723404 (4001 -24);
PAINT GREEN (4001 -24);
FORCEPROP 0 LAST $SEC 2
J 0
(4025 125);
DISPLAY 0.680851 (4025 125);
PAINT MONO (4025 125);
DISPLAY INVISIBLE (4025 125);
FORCEPROP 0 LAST CDS_SEC 2
J 0
(4025 125);
DISPLAY 1.021277 (4025 125);
DISPLAY INVISIBLE (4025 125);
FORCEPROP 0 LASTPIN (3900 200) $PN 3
R 1
J 0
(3890 210);
DISPLAY 0.680851 (3890 210);
PAINT MONO (3890 210);
FORCEPROP 0 LASTPIN (3650 -50) $PN 5
J 2
(3640 -40);
DISPLAY 0.680851 (3640 -40);
PAINT MONO (3640 -40);
FORCEPROP 0 LASTPIN (3900 -200) $PN 4
R 1
J 2
(3890 -210);
DISPLAY 0.680851 (3890 -210);
PAINT MONO (3890 -210);
FORCEPROP 1 LAST MATERIAL IC
J 0
(4001 -149);
DISPLAY 0.723404 (4001 -149);
PAINT GREEN (4001 -149);
FORCEPROP 2 LAST PART_TYPE SMLF
J 0
(4025 75);
DISPLAY 1.021277 (4025 75);
FORCEPROP 2 LAST VALUE PJT138K
J 0
(4025 25);
DISPLAY 1.021277 (4025 25);
FORCEPROP 2 LAST CDS_LIB pure_quanta
J 0
(3850 0);
DISPLAY INVISIBLE (3850 0);
FORCEPROP 1 LAST NEEDS_NO_SIZE TRUE
J 0
(4000 -109);
DISPLAY 0.468085 (4000 -109);
PAINT GREEN (4000 -109);
DISPLAY INVISIBLE (4000 -109);
FORCEPROP 1 LAST CDS_LMAN_SYM_OUTLINE -150,150,150,-150
J 0
(3850 0);
DISPLAY 0.468085 (3850 0);
PAINT GREEN (3850 0);
DISPLAY INVISIBLE (3850 0);
FORCEPROP 1 LAST PATH I168
J 0
(4000 -150);
DISPLAY 0.723404 (4000 -150);
PAINT GREEN (4000 -150);
DISPLAY INVISIBLE (4000 -150);
FORCEPROP 1 LAST PART_NUMBER BAM138K0003
J 0
(4001 -94);
DISPLAY 0.723404 (4001 -94);
PAINT GREEN (4001 -94);
DISPLAY INVISIBLE (4001 -94);
FORCEADD MOSFET_NCH_DUAL..1
(2925 -275);
FORCEPROP 1 LAST LOCATION Q108
J 0
(3076 -301);
DISPLAY 0.723404 (3076 -301);
PAINT GREEN (3076 -301);
FORCEPROP 0 LAST $SEC 1
J 0
(3100 -150);
DISPLAY 0.680851 (3100 -150);
PAINT MONO (3100 -150);
DISPLAY INVISIBLE (3100 -150);
FORCEPROP 2 LAST CDS_SEC 1
J 0
(3100 -150);
DISPLAY 1.021277 (3100 -150);
DISPLAY INVISIBLE (3100 -150);
FORCEPROP 0 LASTPIN (2975 -75) $PN 6
R 1
J 0
(2965 -65);
DISPLAY 0.680851 (2965 -65);
PAINT MONO (2965 -65);
FORCEPROP 0 LASTPIN (2725 -325) $PN 2
J 2
(2715 -315);
DISPLAY 0.680851 (2715 -315);
PAINT MONO (2715 -315);
FORCEPROP 0 LASTPIN (2975 -475) $PN 1
R 1
J 2
(2965 -485);
DISPLAY 0.680851 (2965 -485);
PAINT MONO (2965 -485);
FORCEPROP 1 LAST MATERIAL IC
J 0
(3076 -426);
DISPLAY 0.723404 (3076 -426);
PAINT GREEN (3076 -426);
FORCEPROP 2 LAST PART_TYPE SMLF
J 0
(3100 -200);
DISPLAY 1.021277 (3100 -200);
FORCEPROP 2 LAST VALUE PJT138K
J 0
(3100 -250);
DISPLAY 1.021277 (3100 -250);
FORCEPROP 2 LAST CDS_LIB pure_quanta
J 0
(2925 -275);
DISPLAY INVISIBLE (2925 -275);
FORCEPROP 1 LAST NEEDS_NO_SIZE TRUE
J 0
(2925 -276);
DISPLAY 0.468085 (2925 -276);
PAINT GREEN (2925 -276);
DISPLAY INVISIBLE (2925 -276);
FORCEPROP 1 LAST CDS_LMAN_SYM_OUTLINE -150,150,150,-150
J 0
(2925 -275);
DISPLAY 0.468085 (2925 -275);
PAINT GREEN (2925 -275);
DISPLAY INVISIBLE (2925 -275);
FORCEPROP 1 LAST PATH I169
J 0
(2925 -275);
DISPLAY 0.723404 (2925 -275);
PAINT GREEN (2925 -275);
DISPLAY INVISIBLE (2925 -275);
FORCEPROP 1 LAST PART_NUMBER BAM138K0003
J 0
(3076 -361);
DISPLAY 0.723404 (3076 -361);
PAINT GREEN (3076 -361);
DISPLAY INVISIBLE (3076 -361);
FORCEADD Q_RES..2
(-2975 3525);
FORCEPROP 1 LAST LOCATION R3428
J 0
(-2930 3650);
DISPLAY 0.978723 (-2930 3650);
FORCEPROP 0 LAST $SEC 1
J 0
(-2925 3700);
DISPLAY 0.680851 (-2925 3700);
PAINT MONO (-2925 3700);
DISPLAY INVISIBLE (-2925 3700);
FORCEPROP 0 LAST CDS_SEC 1
J 0
(-2925 3700);
DISPLAY 1.021277 (-2925 3700);
DISPLAY INVISIBLE (-2925 3700);
FORCEPROP 1 LASTPIN (-2975 3625) $PN 1
J 0
(-2970 3587);
DISPLAY 0.787234 (-2970 3587);
PAINT MONO (-2970 3587);
FORCEPROP 1 LASTPIN (-2975 3425) $PN 2
J 0
(-2970 3435);
DISPLAY 0.787234 (-2970 3435);
PAINT MONO (-2970 3435);
FORCEPROP 1 LAST TOLERANCE 1%
J 0
(-2930 3550);
DISPLAY 0.510638 (-2930 3550);
FORCEPROP 1 LAST VALUE 100K
J 0
(-2930 3600);
DISPLAY 0.510638 (-2930 3600);
FORCEPROP 1 LAST MATERIAL EMPTY
J 0
(-2935 3450);
DISPLAY 0.510638 (-2935 3450);
PAINT RED (-2935 3450);
FORCEPROP 1 LAST WATTAGE 1/16W
J 0
(-2935 3500);
DISPLAY 0.510638 (-2935 3500);
FORCEPROP 1 LAST PACK_TYPE 0402LF
J 0
(-2935 3350);
DISPLAY 0.510638 (-2935 3350);
FORCEPROP 2 LAST CDS_LIB pure_quanta
J 0
(-2975 3525);
DISPLAY INVISIBLE (-2975 3525);
FORCEPROP 1 LAST PATH I17
J 0
(-2925 3700);
DISPLAY 0.978723 (-2925 3700);
PAINT WHITE (-2925 3700);
DISPLAY INVISIBLE (-2925 3700);
FORCEPROP 1 LAST PART_NUMBER CS41002FB09
J 0
(-2935 3400);
DISPLAY 0.510638 (-2935 3400);
DISPLAY INVISIBLE (-2935 3400);
FORCEADD OFFPAGE..2
(5075 225);
FORCEPROP 2 LAST $XR0 81 
J 0
(5264 225);
DISPLAY 0.638298 (5264 225);
PAINT MONO (5264 225);
FORCEPROP 2 LAST CDS_LIB standard
J 0
(5075 225);
DISPLAY INVISIBLE (5075 225);
FORCEPROP 1 LAST OFFPAGE TRUE
J 0
(5400 100);
DISPLAY 0.872340 (5400 100);
PAINT AQUA (5400 100);
DISPLAY INVISIBLE (5400 100);
FORCEPROP 1 LAST COMMENT_BODY TRUE
J 0
(5030 130);
DISPLAY 0.872340 (5030 130);
PAINT GREEN (5030 130);
DISPLAY INVISIBLE (5030 130);
FORCEPROP 2 LAST PATH I170
J 0
(5275 275);
DISPLAY 1.021277 (5275 275);
DISPLAY INVISIBLE (5275 275);
FORCEADD Q_CAP..1
(4800 -175);
FORCEPROP 1 LAST LOCATION C1988
J 0
(4850 -75);
DISPLAY 0.638298 (4850 -75);
FORCEPROP 2 LAST $SEC 1
J 0
(4850 25);
DISPLAY 0.680851 (4850 25);
PAINT MONO (4850 25);
DISPLAY INVISIBLE (4850 25);
FORCEPROP 2 LAST CDS_SEC 1
J 0
(4850 25);
DISPLAY 1.021277 (4850 25);
DISPLAY INVISIBLE (4850 25);
FORCEPROP 1 LASTPIN (4800 -75) $PN 1
J 0
(4810 -95);
DISPLAY 0.787234 (4810 -95);
PAINT MONO (4810 -95);
FORCEPROP 1 LASTPIN (4800 -275) $PN 2
J 0
(4810 -295);
DISPLAY 0.787234 (4810 -295);
PAINT MONO (4810 -295);
FORCEPROP 1 LAST VOLTAGE 25V
J 0
(4850 -175);
DISPLAY 0.638298 (4850 -175);
FORCEPROP 1 LAST TOLERANCE 10%
J 0
(4850 -225);
DISPLAY 0.638298 (4850 -225);
FORCEPROP 1 LAST MATERIAL X7R
J 0
(4850 -275);
DISPLAY 0.638298 (4850 -275);
PAINT RED (4850 -275);
FORCEPROP 1 LAST PACK_TYPE 0402
J 0
(4850 -375);
DISPLAY 0.638298 (4850 -375);
FORCEPROP 1 LAST VALUE 0.1UF
J 0
(4850 -125);
DISPLAY 0.638298 (4850 -125);
FORCEPROP 2 LAST CDS_LIB pure_quanta
J 0
(4800 -175);
DISPLAY INVISIBLE (4800 -175);
FORCEPROP 1 LAST PATH I171
J 0
(4850 -25);
DISPLAY 0.978723 (4850 -25);
PAINT WHITE (4850 -25);
DISPLAY INVISIBLE (4850 -25);
FORCEPROP 1 LAST PART_NUMBER CH4104K1B00
J 0
(4850 -325);
DISPLAY 0.638298 (4850 -325);
DISPLAY INVISIBLE (4850 -325);
FORCEADD UNIVERSAL_GND..1
(4800 -375);
FORCEPROP 3 LASTPIN (4800 -325) SIG_NAME GND\g
J 0
(4810 -315);
DISPLAY 0.659574 (4810 -315);
PAINT MONO (4810 -315);
DISPLAY INVISIBLE (4810 -315);
FORCEPROP 2 LAST CDS_LIB pure_quanta_power
J 0
(4800 -375);
DISPLAY INVISIBLE (4800 -375);
FORCEPROP 1 LAST HDL_POWER GND
J 1
(4825 -450);
DISPLAY 0.872340 (4825 -450);
PAINT GREEN (4825 -450);
DISPLAY INVISIBLE (4825 -450);
FORCEPROP 1 LAST PATH I172
J 0
(4875 -375);
DISPLAY 0.872340 (4875 -375);
PAINT AQUA (4875 -375);
DISPLAY INVISIBLE (4875 -375);
FORCEADD UNIVERSAL_POWER..1
(3900 750);
FORCEPROP 3 LASTPIN (3900 700) SIG_NAME P3V3_AUX\g
J 0
(3910 710);
DISPLAY 0.659574 (3910 710);
PAINT MONO (3910 710);
DISPLAY INVISIBLE (3910 710);
FORCEPROP 1 LAST HDL_POWER P3V3_AUX
J 1
(3900 800);
DISPLAY 0.872340 (3900 800);
PAINT GREEN (3900 800);
FORCEPROP 2 LAST CDS_LIB pure_quanta_power
J 0
(3900 750);
DISPLAY INVISIBLE (3900 750);
FORCEPROP 1 LAST PATH I173
J 0
(3950 775);
DISPLAY 0.872340 (3950 775);
PAINT AQUA (3950 775);
DISPLAY INVISIBLE (3950 775);
FORCEADD Q_RES..2
(3900 450);
FORCEPROP 1 LAST LOCATION R3504
J 0
(3945 575);
DISPLAY 0.978723 (3945 575);
FORCEPROP 0 LAST $SEC 1
J 0
(3950 625);
DISPLAY 0.680851 (3950 625);
PAINT MONO (3950 625);
DISPLAY INVISIBLE (3950 625);
FORCEPROP 0 LAST CDS_SEC 1
J 0
(3950 625);
DISPLAY 1.021277 (3950 625);
DISPLAY INVISIBLE (3950 625);
FORCEPROP 1 LASTPIN (3900 550) $PN 1
J 0
(3905 512);
DISPLAY 0.787234 (3905 512);
PAINT MONO (3905 512);
FORCEPROP 1 LASTPIN (3900 350) $PN 2
J 0
(3905 360);
DISPLAY 0.787234 (3905 360);
PAINT MONO (3905 360);
FORCEPROP 1 LAST TOLERANCE 1%
J 0
(3945 475);
DISPLAY 0.638298 (3945 475);
FORCEPROP 1 LAST MATERIAL CHIP
J 0
(3940 375);
DISPLAY 0.638298 (3940 375);
FORCEPROP 1 LAST VALUE 100K
J 0
(3945 525);
DISPLAY 0.638298 (3945 525);
FORCEPROP 1 LAST WATTAGE 1/16W
J 0
(3940 425);
DISPLAY 0.638298 (3940 425);
FORCEPROP 1 LAST PACK_TYPE 0402LF
J 0
(3940 325);
DISPLAY 0.638298 (3940 325);
FORCEPROP 2 LAST CDS_LIB pure_quanta
J 0
(3900 450);
DISPLAY INVISIBLE (3900 450);
FORCEPROP 1 LAST PATH I174
J 0
(3950 625);
DISPLAY 0.978723 (3950 625);
PAINT WHITE (3950 625);
DISPLAY INVISIBLE (3950 625);
FORCEPROP 1 LAST PART_NUMBER CS41002FB09
J 0
(3940 275);
DISPLAY 0.638298 (3940 275);
DISPLAY INVISIBLE (3940 275);
FORCEADD UNIVERSAL_GND..1
(3900 -375);
FORCEPROP 3 LASTPIN (3900 -325) SIG_NAME GND\g
J 0
(3910 -315);
DISPLAY 0.659574 (3910 -315);
PAINT MONO (3910 -315);
DISPLAY INVISIBLE (3910 -315);
FORCEPROP 2 LAST CDS_LIB pure_quanta_power
J 0
(3900 -375);
DISPLAY INVISIBLE (3900 -375);
FORCEPROP 1 LAST HDL_POWER GND
J 1
(3925 -450);
DISPLAY 0.872340 (3925 -450);
PAINT GREEN (3925 -450);
DISPLAY INVISIBLE (3925 -450);
FORCEPROP 1 LAST PATH I175
J 0
(3975 -375);
DISPLAY 0.872340 (3975 -375);
PAINT AQUA (3975 -375);
DISPLAY INVISIBLE (3975 -375);
FORCEADD UNIVERSAL_POWER..1
(2975 500);
FORCEPROP 3 LASTPIN (2975 450) SIG_NAME P3V3_AUX\g
J 0
(2985 460);
DISPLAY 0.659574 (2985 460);
PAINT MONO (2985 460);
DISPLAY INVISIBLE (2985 460);
FORCEPROP 1 LAST HDL_POWER P3V3_AUX
J 1
(2975 550);
DISPLAY 0.872340 (2975 550);
PAINT GREEN (2975 550);
FORCEPROP 2 LAST CDS_LIB pure_quanta_power
J 0
(2975 500);
PAINT MONO (2975 500);
DISPLAY INVISIBLE (2975 500);
FORCEPROP 1 LAST PATH I176
J 0
(3025 525);
DISPLAY 0.872340 (3025 525);
PAINT AQUA (3025 525);
DISPLAY INVISIBLE (3025 525);
FORCEADD Q_RES..2
(2975 200);
FORCEPROP 1 LAST LOCATION R3503
J 0
(3020 325);
DISPLAY 0.638298 (3020 325);
FORCEPROP 2 LAST $SEC 1
J 0
(3025 425);
DISPLAY 0.680851 (3025 425);
PAINT MONO (3025 425);
DISPLAY INVISIBLE (3025 425);
FORCEPROP 2 LAST CDS_SEC 1
J 0
(3025 425);
DISPLAY 1.021277 (3025 425);
DISPLAY INVISIBLE (3025 425);
FORCEPROP 1 LASTPIN (2975 300) $PN 1
J 0
(2980 262);
DISPLAY 0.787234 (2980 262);
FORCEPROP 1 LASTPIN (2975 100) $PN 2
J 0
(2980 110);
DISPLAY 0.787234 (2980 110);
FORCEPROP 1 LAST WATTAGE 1/16W
J 0
(3015 175);
DISPLAY 0.638298 (3015 175);
FORCEPROP 1 LAST VALUE 4.7K
J 0
(3020 275);
DISPLAY 0.638298 (3020 275);
FORCEPROP 1 LAST TOLERANCE 5%
J 0
(3020 225);
DISPLAY 0.638298 (3020 225);
FORCEPROP 1 LAST MATERIAL CHIP
J 0
(3015 125);
DISPLAY 0.638298 (3015 125);
FORCEPROP 1 LAST PACK_TYPE 0402LF
J 0
(3015 75);
DISPLAY 0.638298 (3015 75);
FORCEPROP 2 LAST CDS_LIB pure_quanta
J 0
(2975 200);
PAINT MONO (2975 200);
DISPLAY INVISIBLE (2975 200);
FORCEPROP 1 LAST PATH I177
J 0
(3025 375);
DISPLAY 0.978723 (3025 375);
PAINT WHITE (3025 375);
DISPLAY INVISIBLE (3025 375);
FORCEPROP 1 LAST PART_NUMBER CS24702JB10
J 0
(3015 25);
DISPLAY 0.638298 (3015 25);
DISPLAY INVISIBLE (3015 25);
FORCEADD UNIVERSAL_GND..1
(2975 -650);
FORCEPROP 3 LASTPIN (2975 -600) SIG_NAME GND\g
J 0
(2985 -590);
DISPLAY 0.659574 (2985 -590);
PAINT MONO (2985 -590);
DISPLAY INVISIBLE (2985 -590);
FORCEPROP 2 LAST CDS_LIB pure_quanta_power
J 0
(2975 -650);
DISPLAY INVISIBLE (2975 -650);
FORCEPROP 1 LAST HDL_POWER GND
J 1
(3000 -725);
DISPLAY 0.872340 (3000 -725);
PAINT GREEN (3000 -725);
DISPLAY INVISIBLE (3000 -725);
FORCEPROP 1 LAST PATH I178
J 0
(3050 -650);
DISPLAY 0.872340 (3050 -650);
PAINT AQUA (3050 -650);
DISPLAY INVISIBLE (3050 -650);
FORCEADD UNIVERSAL_POWER..1
(1725 200);
FORCEPROP 3 LASTPIN (1725 150) SIG_NAME P3V3_AUX\g
J 0
(1735 160);
DISPLAY 0.659574 (1735 160);
PAINT MONO (1735 160);
DISPLAY INVISIBLE (1735 160);
FORCEPROP 1 LAST HDL_POWER P3V3_AUX
J 1
(1725 250);
DISPLAY 0.872340 (1725 250);
PAINT GREEN (1725 250);
FORCEPROP 2 LAST CDS_LIB pure_quanta_power
J 0
(1725 200);
PAINT MONO (1725 200);
DISPLAY INVISIBLE (1725 200);
FORCEPROP 1 LAST PATH I179
J 0
(1775 225);
DISPLAY 0.872340 (1775 225);
PAINT AQUA (1775 225);
DISPLAY INVISIBLE (1775 225);
FORCEADD OFFPAGE..4
R 2
(-3250 3725);
FORCEPROP 2 LAST $XR0 122 
J 0
(-3532 3725);
DISPLAY 0.638298 (-3532 3725);
PAINT MONO (-3532 3725);
FORCEPROP 2 LAST CDS_LIB standard
J 0
(-3250 3725);
DISPLAY INVISIBLE (-3250 3725);
FORCEPROP 1 LAST OFFPAGE TRUE
J 2
(-3575 3600);
DISPLAY 0.872340 (-3575 3600);
PAINT GREEN (-3575 3600);
DISPLAY INVISIBLE (-3575 3600);
FORCEPROP 1 LAST COMMENT_BODY TRUE
J 2
(-3225 3625);
DISPLAY 0.872340 (-3225 3625);
PAINT GREEN (-3225 3625);
DISPLAY INVISIBLE (-3225 3625);
FORCEPROP 2 LAST PATH I18
J 0
(-3525 3775);
DISPLAY 1.021277 (-3525 3775);
DISPLAY INVISIBLE (-3525 3775);
FORCEADD Q_RES..2
(1750 -525);
FORCEPROP 1 LAST LOCATION R3502
J 0
(1795 -400);
DISPLAY 0.978723 (1795 -400);
FORCEPROP 0 LAST $SEC 1
J 0
(1800 -350);
DISPLAY 0.680851 (1800 -350);
PAINT MONO (1800 -350);
DISPLAY INVISIBLE (1800 -350);
FORCEPROP 0 LAST CDS_SEC 1
J 0
(1800 -350);
DISPLAY 1.021277 (1800 -350);
DISPLAY INVISIBLE (1800 -350);
FORCEPROP 1 LASTPIN (1750 -425) $PN 1
J 0
(1755 -463);
DISPLAY 0.787234 (1755 -463);
PAINT MONO (1755 -463);
FORCEPROP 1 LASTPIN (1750 -625) $PN 2
J 0
(1755 -615);
DISPLAY 0.787234 (1755 -615);
PAINT MONO (1755 -615);
FORCEPROP 1 LAST MATERIAL EMPTY
J 0
(1790 -600);
DISPLAY 0.510638 (1790 -600);
PAINT RED (1790 -600);
FORCEPROP 1 LAST WATTAGE 1/16W
J 0
(1790 -550);
DISPLAY 0.510638 (1790 -550);
FORCEPROP 1 LAST TOLERANCE 1%
J 0
(1795 -500);
DISPLAY 0.510638 (1795 -500);
FORCEPROP 1 LAST VALUE 100K
J 0
(1795 -450);
DISPLAY 0.510638 (1795 -450);
FORCEPROP 1 LAST PACK_TYPE 0402LF
J 0
(1790 -700);
DISPLAY 0.510638 (1790 -700);
FORCEPROP 2 LAST CDS_LIB pure_quanta
J 0
(1750 -525);
DISPLAY INVISIBLE (1750 -525);
FORCEPROP 1 LAST PATH I181
J 0
(1800 -350);
DISPLAY 0.978723 (1800 -350);
PAINT WHITE (1800 -350);
DISPLAY INVISIBLE (1800 -350);
FORCEPROP 1 LAST PART_NUMBER CS41002FB09
J 0
(1790 -650);
DISPLAY 0.510638 (1790 -650);
DISPLAY INVISIBLE (1790 -650);
FORCEADD UNIVERSAL_GND..1
(1750 -725);
FORCEPROP 3 LASTPIN (1750 -675) SIG_NAME GND\g
J 0
(1760 -665);
DISPLAY 0.659574 (1760 -665);
PAINT MONO (1760 -665);
DISPLAY INVISIBLE (1760 -665);
FORCEPROP 2 LAST CDS_LIB pure_quanta_power
J 0
(1750 -725);
DISPLAY INVISIBLE (1750 -725);
FORCEPROP 1 LAST HDL_POWER GND
J 1
(1775 -800);
DISPLAY 0.872340 (1775 -800);
PAINT GREEN (1775 -800);
DISPLAY INVISIBLE (1775 -800);
FORCEPROP 1 LAST PATH I182
J 0
(1825 -725);
DISPLAY 0.872340 (1825 -725);
PAINT AQUA (1825 -725);
DISPLAY INVISIBLE (1825 -725);
FORCEADD OFFPAGE..4
R 2
(1450 -325);
FORCEPROP 2 LAST $XR0 119 
J 0
(1198 -325);
DISPLAY 0.638298 (1198 -325);
PAINT MONO (1198 -325);
FORCEPROP 2 LAST CDS_LIB standard
J 0
(1450 -325);
DISPLAY INVISIBLE (1450 -325);
FORCEPROP 1 LAST OFFPAGE TRUE
J 2
(1125 -450);
DISPLAY 0.872340 (1125 -450);
PAINT GREEN (1125 -450);
DISPLAY INVISIBLE (1125 -450);
FORCEPROP 1 LAST COMMENT_BODY TRUE
J 2
(1475 -425);
DISPLAY 0.872340 (1475 -425);
PAINT GREEN (1475 -425);
DISPLAY INVISIBLE (1475 -425);
FORCEPROP 2 LAST PATH I183
J 0
(1200 -275);
DISPLAY 1.021277 (1200 -275);
DISPLAY INVISIBLE (1200 -275);
FORCEADD Q_RES..2
(1725 -100);
FORCEPROP 1 LAST LOCATION R3525
J 0
(1770 25);
DISPLAY 0.978723 (1770 25);
FORCEPROP 0 LAST $SEC 1
J 0
(1775 75);
DISPLAY 0.680851 (1775 75);
PAINT MONO (1775 75);
DISPLAY INVISIBLE (1775 75);
FORCEPROP 0 LAST CDS_SEC 1
J 0
(1775 75);
DISPLAY 1.021277 (1775 75);
DISPLAY INVISIBLE (1775 75);
FORCEPROP 1 LASTPIN (1725 0) $PN 1
J 0
(1730 -38);
DISPLAY 0.787234 (1730 -38);
PAINT MONO (1730 -38);
FORCEPROP 1 LASTPIN (1725 -200) $PN 2
J 0
(1730 -190);
DISPLAY 0.787234 (1730 -190);
PAINT MONO (1730 -190);
FORCEPROP 1 LAST PACK_TYPE 0402LF
J 0
(1765 -275);
DISPLAY 0.787234 (1765 -275);
FORCEPROP 1 LAST VALUE 54.9K
J 0
(1770 -25);
DISPLAY 0.787234 (1770 -25);
FORCEPROP 1 LAST TOLERANCE 1%
J 0
(1770 -75);
DISPLAY 0.787234 (1770 -75);
FORCEPROP 1 LAST MATERIAL CHIP
J 0
(1765 -175);
DISPLAY 0.787234 (1765 -175);
FORCEPROP 1 LAST WATTAGE 1/16W
J 0
(1765 -125);
DISPLAY 0.787234 (1765 -125);
FORCEPROP 2 LAST CDS_LIB pure_quanta
J 0
(1725 -100);
DISPLAY INVISIBLE (1725 -100);
FORCEPROP 1 LAST PATH I184
J 0
(1775 75);
DISPLAY 0.978723 (1775 75);
PAINT WHITE (1775 75);
DISPLAY INVISIBLE (1775 75);
FORCEPROP 1 LAST PART_NUMBER CS35492FB03
J 0
(1765 -225);
DISPLAY 0.787234 (1765 -225);
DISPLAY INVISIBLE (1765 -225);
FORCEADD OFFPAGE..2
(3475 1950);
FORCEPROP 2 LAST $XR0 242 
J 0
(3664 1950);
DISPLAY 0.638298 (3664 1950);
PAINT MONO (3664 1950);
FORCEPROP 2 LAST CDS_LIB standard
J 0
(3475 1950);
DISPLAY INVISIBLE (3475 1950);
FORCEPROP 1 LAST OFFPAGE TRUE
J 0
(3800 1825);
DISPLAY 0.872340 (3800 1825);
PAINT AQUA (3800 1825);
DISPLAY INVISIBLE (3800 1825);
FORCEPROP 1 LAST COMMENT_BODY TRUE
J 0
(3430 1855);
DISPLAY 0.872340 (3430 1855);
PAINT GREEN (3430 1855);
DISPLAY INVISIBLE (3430 1855);
FORCEPROP 2 LAST PATH I185
J 0
(3650 2025);
DISPLAY 1.021277 (3650 2025);
DISPLAY INVISIBLE (3650 2025);
FORCEADD UNIVERSAL_GND..1
(1600 2775);
FORCEPROP 3 LASTPIN (1600 2825) SIG_NAME GND\g
J 0
(1610 2835);
DISPLAY 0.659574 (1610 2835);
PAINT MONO (1610 2835);
DISPLAY INVISIBLE (1610 2835);
FORCEPROP 2 LAST CDS_LIB pure_quanta_power
J 0
(1600 2775);
DISPLAY INVISIBLE (1600 2775);
FORCEPROP 1 LAST HDL_POWER GND
J 1
(1625 2700);
DISPLAY 0.872340 (1625 2700);
PAINT GREEN (1625 2700);
DISPLAY INVISIBLE (1625 2700);
FORCEPROP 1 LAST PATH I186
J 0
(1675 2775);
DISPLAY 0.872340 (1675 2775);
PAINT AQUA (1675 2775);
DISPLAY INVISIBLE (1675 2775);
FORCEADD Q_RES..2
(1600 3050);
FORCEPROP 1 LAST LOCATION R3471
J 0
(1645 3175);
DISPLAY 0.978723 (1645 3175);
FORCEPROP 0 LAST $SEC 1
J 0
(1650 3225);
DISPLAY 0.680851 (1650 3225);
PAINT MONO (1650 3225);
DISPLAY INVISIBLE (1650 3225);
FORCEPROP 0 LAST CDS_SEC 1
J 0
(1650 3225);
DISPLAY 1.021277 (1650 3225);
DISPLAY INVISIBLE (1650 3225);
FORCEPROP 1 LASTPIN (1600 3150) $PN 1
J 0
(1605 3112);
DISPLAY 0.787234 (1605 3112);
PAINT MONO (1605 3112);
FORCEPROP 1 LASTPIN (1600 2950) $PN 2
J 0
(1605 2960);
DISPLAY 0.787234 (1605 2960);
PAINT MONO (1605 2960);
FORCEPROP 1 LAST VALUE 10K
J 0
(1645 3125);
DISPLAY 0.510638 (1645 3125);
FORCEPROP 1 LAST WATTAGE 1/16W
J 0
(1640 3025);
DISPLAY 0.510638 (1640 3025);
FORCEPROP 1 LAST TOLERANCE 1%
J 0
(1645 3075);
DISPLAY 0.510638 (1645 3075);
FORCEPROP 1 LAST MATERIAL EMPTY
J 0
(1640 2975);
DISPLAY 0.510638 (1640 2975);
PAINT RED (1640 2975);
FORCEPROP 1 LAST PACK_TYPE 0402LF
J 0
(1640 2875);
DISPLAY 0.510638 (1640 2875);
FORCEPROP 2 LAST CDS_LIB pure_quanta
J 0
(1600 3050);
DISPLAY INVISIBLE (1600 3050);
FORCEPROP 1 LAST PATH I187
J 0
(1650 3225);
DISPLAY 0.978723 (1650 3225);
PAINT WHITE (1650 3225);
DISPLAY INVISIBLE (1650 3225);
FORCEPROP 1 LAST PART_NUMBER CS31002FB08
J 0
(1640 2925);
DISPLAY 0.510638 (1640 2925);
DISPLAY INVISIBLE (1640 2925);
FORCEADD OFFPAGE..4
R 2
(1325 3325);
FORCEPROP 2 LAST $XR0 81 
J 0
(1104 3325);
DISPLAY 0.638298 (1104 3325);
PAINT MONO (1104 3325);
FORCEPROP 2 LAST CDS_LIB standard
J 0
(1325 3325);
DISPLAY INVISIBLE (1325 3325);
FORCEPROP 1 LAST OFFPAGE TRUE
J 2
(1000 3200);
DISPLAY 0.872340 (1000 3200);
PAINT GREEN (1000 3200);
DISPLAY INVISIBLE (1000 3200);
FORCEPROP 1 LAST COMMENT_BODY TRUE
J 2
(1350 3225);
DISPLAY 0.872340 (1350 3225);
PAINT GREEN (1350 3225);
DISPLAY INVISIBLE (1350 3225);
FORCEPROP 2 LAST PATH I188
J 0
(1075 3375);
DISPLAY 0.680851 (1075 3375);
DISPLAY INVISIBLE (1075 3375);
FORCEADD UNIVERSAL_POWER..1
(1575 3850);
FORCEPROP 3 LASTPIN (1575 3800) SIG_NAME P3V3_AUX\g
J 0
(1585 3810);
DISPLAY 0.659574 (1585 3810);
PAINT MONO (1585 3810);
DISPLAY INVISIBLE (1585 3810);
FORCEPROP 1 LAST HDL_POWER P3V3_AUX
J 1
(1575 3900);
DISPLAY 0.872340 (1575 3900);
PAINT GREEN (1575 3900);
FORCEPROP 2 LAST CDS_LIB pure_quanta_power
J 0
(1575 3850);
PAINT MONO (1575 3850);
DISPLAY INVISIBLE (1575 3850);
FORCEPROP 1 LAST PATH I190
J 0
(1625 3875);
DISPLAY 0.872340 (1625 3875);
PAINT AQUA (1625 3875);
DISPLAY INVISIBLE (1625 3875);
FORCEADD UNIVERSAL_GND..1
(2750 3000);
FORCEPROP 3 LASTPIN (2750 3050) SIG_NAME GND\g
J 0
(2760 3060);
DISPLAY 0.659574 (2760 3060);
PAINT MONO (2760 3060);
DISPLAY INVISIBLE (2760 3060);
FORCEPROP 2 LAST CDS_LIB pure_quanta_power
J 0
(2750 3000);
DISPLAY INVISIBLE (2750 3000);
FORCEPROP 1 LAST HDL_POWER GND
J 1
(2775 2925);
DISPLAY 0.872340 (2775 2925);
PAINT GREEN (2775 2925);
DISPLAY INVISIBLE (2775 2925);
FORCEPROP 1 LAST PATH I191
J 0
(2825 3000);
DISPLAY 0.872340 (2825 3000);
PAINT AQUA (2825 3000);
DISPLAY INVISIBLE (2825 3000);
FORCEADD Q_RES..2
(2750 3875);
FORCEPROP 1 LAST LOCATION R9043
J 0
(2795 4000);
DISPLAY 0.638298 (2795 4000);
FORCEPROP 0 LAST $SEC 1
J 0
(2800 4050);
DISPLAY 0.680851 (2800 4050);
PAINT MONO (2800 4050);
DISPLAY INVISIBLE (2800 4050);
FORCEPROP 0 LAST CDS_SEC 1
J 0
(2800 4050);
DISPLAY 0.680851 (2800 4050);
DISPLAY INVISIBLE (2800 4050);
FORCEPROP 1 LASTPIN (2750 3975) $PN 1
J 0
(2755 3937);
DISPLAY 0.787234 (2755 3937);
PAINT MONO (2755 3937);
FORCEPROP 1 LASTPIN (2750 3775) $PN 2
J 0
(2755 3785);
DISPLAY 0.787234 (2755 3785);
PAINT MONO (2755 3785);
FORCEPROP 1 LAST VALUE 4.7K
J 0
(2795 3950);
DISPLAY 0.638298 (2795 3950);
FORCEPROP 1 LAST WATTAGE 1/16W
J 0
(2790 3850);
DISPLAY 0.638298 (2790 3850);
FORCEPROP 1 LAST PACK_TYPE 0402LF
J 0
(2790 3750);
DISPLAY 0.638298 (2790 3750);
FORCEPROP 1 LAST MATERIAL CHIP
J 0
(2790 3800);
DISPLAY 0.638298 (2790 3800);
FORCEPROP 1 LAST TOLERANCE 5%
J 0
(2795 3900);
DISPLAY 0.638298 (2795 3900);
FORCEPROP 2 LAST CDS_LIB pure_quanta
J 0
(2750 3875);
DISPLAY INVISIBLE (2750 3875);
FORCEPROP 1 LAST PATH I192
J 0
(2800 4050);
DISPLAY 0.978723 (2800 4050);
PAINT WHITE (2800 4050);
DISPLAY INVISIBLE (2800 4050);
FORCEPROP 1 LAST PART_NUMBER CS24702JB10
J 0
(2790 3700);
DISPLAY 0.638298 (2790 3700);
DISPLAY INVISIBLE (2790 3700);
FORCEADD UNIVERSAL_POWER..1
(2750 4175);
FORCEPROP 3 LASTPIN (2750 4125) SIG_NAME P3V3_AUX\g
J 0
(2760 4135);
DISPLAY 0.659574 (2760 4135);
PAINT MONO (2760 4135);
DISPLAY INVISIBLE (2760 4135);
FORCEPROP 1 LAST HDL_POWER P3V3_AUX
J 1
(2750 4225);
DISPLAY 0.872340 (2750 4225);
PAINT GREEN (2750 4225);
FORCEPROP 2 LAST CDS_LIB pure_quanta_power
J 0
(2750 4175);
DISPLAY INVISIBLE (2750 4175);
FORCEPROP 1 LAST PATH I193
J 0
(2800 4200);
DISPLAY 0.872340 (2800 4200);
PAINT AQUA (2800 4200);
DISPLAY INVISIBLE (2800 4200);
FORCEADD UNIVERSAL_GND..1
(3725 3300);
FORCEPROP 3 LASTPIN (3725 3350) SIG_NAME GND\g
J 0
(3735 3360);
DISPLAY 0.659574 (3735 3360);
PAINT MONO (3735 3360);
DISPLAY INVISIBLE (3735 3360);
FORCEPROP 2 LAST CDS_LIB pure_quanta_power
J 0
(3725 3300);
DISPLAY INVISIBLE (3725 3300);
FORCEPROP 1 LAST HDL_POWER GND
J 1
(3750 3225);
DISPLAY 0.872340 (3750 3225);
PAINT GREEN (3750 3225);
DISPLAY INVISIBLE (3750 3225);
FORCEPROP 1 LAST PATH I194
J 0
(3800 3300);
DISPLAY 0.872340 (3800 3300);
PAINT AQUA (3800 3300);
DISPLAY INVISIBLE (3800 3300);
FORCEADD Q_RES..2
(3725 4175);
FORCEPROP 1 LAST LOCATION R9044
J 0
(3770 4300);
DISPLAY 0.638298 (3770 4300);
FORCEPROP 0 LAST $SEC 1
J 0
(3775 4350);
DISPLAY 0.680851 (3775 4350);
PAINT MONO (3775 4350);
DISPLAY INVISIBLE (3775 4350);
FORCEPROP 0 LAST CDS_SEC 1
J 0
(3775 4350);
DISPLAY 0.680851 (3775 4350);
DISPLAY INVISIBLE (3775 4350);
FORCEPROP 1 LASTPIN (3725 4275) $PN 1
J 0
(3730 4237);
DISPLAY 0.787234 (3730 4237);
PAINT MONO (3730 4237);
FORCEPROP 1 LASTPIN (3725 4075) $PN 2
J 0
(3730 4085);
DISPLAY 0.787234 (3730 4085);
PAINT MONO (3730 4085);
FORCEPROP 1 LAST MATERIAL EMPTY
J 0
(3765 4100);
DISPLAY 0.510638 (3765 4100);
PAINT RED (3765 4100);
FORCEPROP 1 LAST PACK_TYPE 0402LF
J 0
(3765 4000);
DISPLAY 0.510638 (3765 4000);
FORCEPROP 1 LAST VALUE 4.7K
J 0
(3770 4250);
DISPLAY 0.510638 (3770 4250);
FORCEPROP 1 LAST WATTAGE 1/16W
J 0
(3765 4150);
DISPLAY 0.510638 (3765 4150);
FORCEPROP 1 LAST TOLERANCE 1%
J 0
(3770 4200);
DISPLAY 0.510638 (3770 4200);
FORCEPROP 2 LAST CDS_LIB pure_quanta
J 0
(3725 4175);
DISPLAY INVISIBLE (3725 4175);
FORCEPROP 1 LAST PATH I195
J 0
(3775 4350);
DISPLAY 0.978723 (3775 4350);
PAINT WHITE (3775 4350);
DISPLAY INVISIBLE (3775 4350);
FORCEPROP 1 LAST PART_NUMBER CS24702FB06
J 0
(3765 4050);
DISPLAY 0.510638 (3765 4050);
DISPLAY INVISIBLE (3765 4050);
FORCEADD UNIVERSAL_POWER..1
(3725 4475);
FORCEPROP 3 LASTPIN (3725 4425) SIG_NAME P3V3_AUX\g
J 0
(3735 4435);
DISPLAY 0.659574 (3735 4435);
PAINT MONO (3735 4435);
DISPLAY INVISIBLE (3735 4435);
FORCEPROP 1 LAST HDL_POWER P3V3_AUX
J 1
(3725 4525);
DISPLAY 0.872340 (3725 4525);
PAINT GREEN (3725 4525);
FORCEPROP 2 LAST CDS_LIB pure_quanta_power
J 0
(3725 4475);
DISPLAY INVISIBLE (3725 4475);
FORCEPROP 1 LAST PATH I196
J 0
(3775 4500);
DISPLAY 0.872340 (3775 4500);
PAINT AQUA (3775 4500);
DISPLAY INVISIBLE (3775 4500);
FORCEADD UNIVERSAL_GND..1
(4600 3400);
FORCEPROP 3 LASTPIN (4600 3450) SIG_NAME GND\g
J 0
(4610 3460);
DISPLAY 0.659574 (4610 3460);
PAINT MONO (4610 3460);
DISPLAY INVISIBLE (4610 3460);
FORCEPROP 2 LAST CDS_LIB pure_quanta_power
J 0
(4600 3400);
DISPLAY INVISIBLE (4600 3400);
FORCEPROP 1 LAST HDL_POWER GND
J 1
(4625 3325);
DISPLAY 0.872340 (4625 3325);
PAINT GREEN (4625 3325);
DISPLAY INVISIBLE (4625 3325);
FORCEPROP 1 LAST PATH I197
J 0
(4675 3400);
DISPLAY 0.872340 (4675 3400);
PAINT AQUA (4675 3400);
DISPLAY INVISIBLE (4675 3400);
FORCEADD Q_RES..1
R 1
(4600 3675);
FORCEPROP 1 LAST LOCATION R3472
J 0
(4650 3675);
DISPLAY 0.787234 (4650 3675);
FORCEPROP 0 LAST $SEC 1
R 1
J 0
(4650 3825);
DISPLAY 0.680851 (4650 3825);
PAINT MONO (4650 3825);
DISPLAY INVISIBLE (4650 3825);
FORCEPROP 0 LAST CDS_SEC 1
R 1
J 0
(4650 3825);
DISPLAY 1.021277 (4650 3825);
DISPLAY INVISIBLE (4650 3825);
FORCEPROP 1 LASTPIN (4600 3575) $PN 1
R 1
J 0
(4588 3587);
DISPLAY 0.787234 (4588 3587);
PAINT MONO (4588 3587);
FORCEPROP 1 LASTPIN (4600 3775) $PN 2
R 1
J 0
(4588 3737);
DISPLAY 0.787234 (4588 3737);
PAINT MONO (4588 3737);
FORCEPROP 1 LAST VALUE 0
J 2
(4700 3725);
DISPLAY 0.638298 (4700 3725);
FORCEPROP 1 LAST MATERIAL EMPTY
J 0
(4675 3525);
DISPLAY 0.638298 (4675 3525);
PAINT RED (4675 3525);
FORCEPROP 1 LAST TOLERANCE 5%
J 0
(4675 3575);
DISPLAY 0.638298 (4675 3575);
FORCEPROP 1 LAST PACK_TYPE 0402LF
J 0
(4675 3625);
DISPLAY 0.638298 (4675 3625);
FORCEPROP 2 LAST CDS_LIB pure_quanta
R 1
J 0
(4600 3675);
DISPLAY INVISIBLE (4600 3675);
FORCEPROP 1 LAST WATTAGE 1/16W
R 1
J 2
(4475 3850);
DISPLAY 0.638298 (4475 3850);
DISPLAY INVISIBLE (4475 3850);
FORCEPROP 1 LAST PATH I198
R 1
J 0
(4450 3625);
DISPLAY 0.978723 (4450 3625);
PAINT WHITE (4450 3625);
DISPLAY INVISIBLE (4450 3625);
FORCEPROP 1 LAST PART_NUMBER CS00002JB13
J 0
(4650 3775);
DISPLAY 0.638298 (4650 3775);
DISPLAY INVISIBLE (4650 3775);
FORCEADD OFFPAGE..2
(4800 3975);
FORCEPROP 2 LAST $XR0 115 
J 0
(4989 3975);
DISPLAY 0.638298 (4989 3975);
PAINT MONO (4989 3975);
FORCEPROP 2 LAST CDS_LIB standard
J 0
(4800 3975);
DISPLAY INVISIBLE (4800 3975);
FORCEPROP 1 LAST OFFPAGE TRUE
J 0
(5125 3850);
DISPLAY 0.872340 (5125 3850);
PAINT AQUA (5125 3850);
DISPLAY INVISIBLE (5125 3850);
FORCEPROP 1 LAST COMMENT_BODY TRUE
J 0
(4755 3880);
DISPLAY 0.872340 (4755 3880);
PAINT GREEN (4755 3880);
DISPLAY INVISIBLE (4755 3880);
FORCEPROP 2 LAST PATH I199
J 0
(5000 4025);
DISPLAY 0.680851 (5000 4025);
DISPLAY INVISIBLE (5000 4025);
FORCEADD UNIVERSAL_GND..1
(-2950 -1000);
FORCEPROP 3 LASTPIN (-2950 -950) SIG_NAME GND\g
J 0
(-2940 -940);
DISPLAY 0.659574 (-2940 -940);
PAINT MONO (-2940 -940);
DISPLAY INVISIBLE (-2940 -940);
FORCEPROP 2 LAST CDS_LIB pure_quanta_power
J 0
(-2950 -1000);
DISPLAY INVISIBLE (-2950 -1000);
FORCEPROP 1 LAST HDL_POWER GND
J 1
(-2925 -1075);
DISPLAY 0.872340 (-2925 -1075);
PAINT GREEN (-2925 -1075);
DISPLAY INVISIBLE (-2925 -1075);
FORCEPROP 1 LAST PATH I2
J 0
(-2875 -1000);
DISPLAY 0.872340 (-2875 -1000);
PAINT AQUA (-2875 -1000);
DISPLAY INVISIBLE (-2875 -1000);
FORCEADD UNIVERSAL_POWER..1
(-3000 4250);
FORCEPROP 3 LASTPIN (-3000 4200) SIG_NAME P3V3_AUX\g
J 0
(-2990 4210);
DISPLAY 0.659574 (-2990 4210);
PAINT MONO (-2990 4210);
DISPLAY INVISIBLE (-2990 4210);
FORCEPROP 1 LAST HDL_POWER P3V3_AUX
J 1
(-3000 4300);
DISPLAY 0.872340 (-3000 4300);
PAINT GREEN (-3000 4300);
FORCEPROP 2 LAST CDS_LIB pure_quanta_power
J 0
(-3000 4250);
PAINT MONO (-3000 4250);
DISPLAY INVISIBLE (-3000 4250);
FORCEPROP 1 LAST PATH I20
J 0
(-2950 4275);
DISPLAY 0.872340 (-2950 4275);
PAINT AQUA (-2950 4275);
DISPLAY INVISIBLE (-2950 4275);
FORCEADD MOSFET_NCH_DUAL..2
(3675 3675);
FORCEPROP 1 LAST LOCATION Q106
J 0
(3826 3651);
DISPLAY 0.723404 (3826 3651);
PAINT GREEN (3826 3651);
FORCEPROP 0 LAST $SEC 2
J 0
(3850 3800);
DISPLAY 0.680851 (3850 3800);
PAINT MONO (3850 3800);
DISPLAY INVISIBLE (3850 3800);
FORCEPROP 0 LAST CDS_SEC 2
J 0
(3850 3800);
DISPLAY 0.680851 (3850 3800);
DISPLAY INVISIBLE (3850 3800);
FORCEPROP 0 LASTPIN (3725 3875) $PN 3
R 1
J 0
(3715 3885);
DISPLAY 0.680851 (3715 3885);
PAINT MONO (3715 3885);
FORCEPROP 0 LASTPIN (3475 3625) $PN 5
J 2
(3465 3635);
DISPLAY 0.680851 (3465 3635);
PAINT MONO (3465 3635);
FORCEPROP 0 LASTPIN (3725 3475) $PN 4
R 1
J 2
(3715 3465);
DISPLAY 0.680851 (3715 3465);
PAINT MONO (3715 3465);
FORCEPROP 1 LAST MATERIAL IC
J 0
(3826 3526);
DISPLAY 0.723404 (3826 3526);
PAINT GREEN (3826 3526);
FORCEPROP 2 LAST VALUE PJT138K
J 0
(3850 3700);
DISPLAY 1.021277 (3850 3700);
FORCEPROP 2 LAST PART_TYPE SMLF
J 0
(3850 3750);
DISPLAY 1.021277 (3850 3750);
FORCEPROP 1 LAST NEEDS_NO_SIZE TRUE
J 0
(3825 3566);
DISPLAY 0.468085 (3825 3566);
PAINT GREEN (3825 3566);
DISPLAY INVISIBLE (3825 3566);
FORCEPROP 1 LAST CDS_LMAN_SYM_OUTLINE -150,150,150,-150
J 0
(3675 3675);
DISPLAY 0.468085 (3675 3675);
PAINT GREEN (3675 3675);
DISPLAY INVISIBLE (3675 3675);
FORCEPROP 2 LAST CDS_LIB pure_quanta
J 0
(3675 3675);
DISPLAY INVISIBLE (3675 3675);
FORCEPROP 1 LAST PATH I200
J 0
(3825 3525);
DISPLAY 0.723404 (3825 3525);
PAINT GREEN (3825 3525);
DISPLAY INVISIBLE (3825 3525);
FORCEPROP 1 LAST PART_NUMBER BAM138K0003
J 0
(3826 3581);
DISPLAY 0.723404 (3826 3581);
PAINT GREEN (3826 3581);
DISPLAY INVISIBLE (3826 3581);
FORCEADD MOSFET_NCH_DUAL..1
(2700 3375);
FORCEPROP 1 LAST LOCATION Q106
J 0
(2851 3349);
DISPLAY 0.723404 (2851 3349);
PAINT GREEN (2851 3349);
FORCEPROP 0 LAST $SEC 1
J 0
(2875 3500);
DISPLAY 0.680851 (2875 3500);
PAINT MONO (2875 3500);
DISPLAY INVISIBLE (2875 3500);
FORCEPROP 0 LAST CDS_SEC 1
J 0
(2875 3500);
DISPLAY 0.680851 (2875 3500);
DISPLAY INVISIBLE (2875 3500);
FORCEPROP 0 LASTPIN (2750 3575) $PN 6
R 1
J 0
(2740 3585);
DISPLAY 0.680851 (2740 3585);
PAINT MONO (2740 3585);
FORCEPROP 0 LASTPIN (2500 3325) $PN 2
J 2
(2490 3335);
DISPLAY 0.680851 (2490 3335);
PAINT MONO (2490 3335);
FORCEPROP 0 LASTPIN (2750 3175) $PN 1
R 1
J 2
(2740 3165);
DISPLAY 0.680851 (2740 3165);
PAINT MONO (2740 3165);
FORCEPROP 2 LAST VALUE PJT138K
J 0
(2875 3400);
DISPLAY 1.021277 (2875 3400);
FORCEPROP 2 LAST PART_TYPE SMLF
J 0
(2875 3450);
DISPLAY 1.021277 (2875 3450);
FORCEPROP 1 LAST MATERIAL IC
J 0
(2851 3224);
DISPLAY 0.723404 (2851 3224);
PAINT GREEN (2851 3224);
FORCEPROP 1 LAST NEEDS_NO_SIZE TRUE
J 0
(2700 3374);
DISPLAY 0.468085 (2700 3374);
PAINT GREEN (2700 3374);
DISPLAY INVISIBLE (2700 3374);
FORCEPROP 1 LAST CDS_LMAN_SYM_OUTLINE -150,150,150,-150
J 0
(2700 3375);
DISPLAY 0.468085 (2700 3375);
PAINT GREEN (2700 3375);
DISPLAY INVISIBLE (2700 3375);
FORCEPROP 2 LAST CDS_LIB pure_quanta
J 0
(2700 3375);
DISPLAY INVISIBLE (2700 3375);
FORCEPROP 1 LAST PATH I201
J 0
(2700 3375);
DISPLAY 0.723404 (2700 3375);
PAINT GREEN (2700 3375);
DISPLAY INVISIBLE (2700 3375);
FORCEPROP 1 LAST PART_NUMBER BAM138K0003
J 0
(2851 3289);
DISPLAY 0.723404 (2851 3289);
PAINT GREEN (2851 3289);
DISPLAY INVISIBLE (2851 3289);
FORCEADD Q_RES..2
(1575 3600);
FORCEPROP 1 LAST LOCATION R3470
J 0
(1620 3725);
DISPLAY 0.978723 (1620 3725);
FORCEPROP 0 LAST $SEC 1
J 0
(1625 3775);
DISPLAY 0.680851 (1625 3775);
PAINT MONO (1625 3775);
DISPLAY INVISIBLE (1625 3775);
FORCEPROP 0 LAST CDS_SEC 1
J 0
(1625 3775);
DISPLAY 0.680851 (1625 3775);
DISPLAY INVISIBLE (1625 3775);
FORCEPROP 1 LASTPIN (1575 3700) $PN 1
J 0
(1580 3662);
DISPLAY 0.787234 (1580 3662);
PAINT MONO (1580 3662);
FORCEPROP 1 LASTPIN (1575 3500) $PN 2
J 0
(1580 3510);
DISPLAY 0.787234 (1580 3510);
PAINT MONO (1580 3510);
FORCEPROP 1 LAST VALUE 1K
J 0
(1620 3675);
DISPLAY 0.723404 (1620 3675);
FORCEPROP 1 LAST TOLERANCE 1%
J 0
(1620 3625);
DISPLAY 0.723404 (1620 3625);
FORCEPROP 1 LAST PACK_TYPE 0402LF
J 0
(1625 3475);
DISPLAY 0.723404 (1625 3475);
FORCEPROP 1 LAST MATERIAL CHIP
J 0
(1615 3525);
DISPLAY 0.723404 (1615 3525);
FORCEPROP 1 LAST WATTAGE 1/16W
J 0
(1615 3575);
DISPLAY 0.723404 (1615 3575);
FORCEPROP 2 LAST CDS_LIB pure_quanta
J 0
(1575 3600);
DISPLAY INVISIBLE (1575 3600);
FORCEPROP 1 LAST PATH I202
J 0
(1625 3775);
DISPLAY 0.978723 (1625 3775);
PAINT WHITE (1625 3775);
DISPLAY INVISIBLE (1625 3775);
FORCEPROP 1 LAST PART_NUMBER CS21002FB06
J 0
(1615 3475);
DISPLAY 0.723404 (1615 3475);
PAINT WHITE (1615 3475);
DISPLAY INVISIBLE (1615 3475);
FORCEADD MOSFET_NCH_DUAL..1
(-1775 -550);
FORCEPROP 1 LAST LOCATION Q104
J 0
(-1624 -576);
DISPLAY 0.723404 (-1624 -576);
PAINT GREEN (-1624 -576);
FORCEPROP 0 LAST $SEC 1
J 0
(-1600 -425);
DISPLAY 0.680851 (-1600 -425);
PAINT MONO (-1600 -425);
DISPLAY INVISIBLE (-1600 -425);
FORCEPROP 2 LAST CDS_SEC 1
J 0
(-1600 -425);
DISPLAY 1.021277 (-1600 -425);
DISPLAY INVISIBLE (-1600 -425);
FORCEPROP 0 LASTPIN (-1725 -350) $PN 6
R 1
J 0
(-1735 -340);
DISPLAY 0.680851 (-1735 -340);
PAINT MONO (-1735 -340);
FORCEPROP 0 LASTPIN (-1975 -600) $PN 2
J 2
(-1985 -590);
DISPLAY 0.680851 (-1985 -590);
PAINT MONO (-1985 -590);
FORCEPROP 0 LASTPIN (-1725 -750) $PN 1
R 1
J 2
(-1735 -760);
DISPLAY 0.680851 (-1735 -760);
PAINT MONO (-1735 -760);
FORCEPROP 2 LAST VALUE PJT138K
J 0
(-1600 -525);
DISPLAY 1.021277 (-1600 -525);
FORCEPROP 1 LAST MATERIAL IC
J 0
(-1624 -701);
DISPLAY 0.723404 (-1624 -701);
PAINT GREEN (-1624 -701);
FORCEPROP 2 LAST PART_TYPE SMLF
J 0
(-1600 -475);
DISPLAY 1.021277 (-1600 -475);
FORCEPROP 2 LAST CDS_LIB pure_quanta
J 0
(-1775 -550);
DISPLAY INVISIBLE (-1775 -550);
FORCEPROP 1 LAST NEEDS_NO_SIZE TRUE
J 0
(-1775 -551);
DISPLAY 0.468085 (-1775 -551);
PAINT GREEN (-1775 -551);
DISPLAY INVISIBLE (-1775 -551);
FORCEPROP 1 LAST CDS_LMAN_SYM_OUTLINE -150,150,150,-150
J 0
(-1775 -550);
DISPLAY 0.468085 (-1775 -550);
PAINT GREEN (-1775 -550);
DISPLAY INVISIBLE (-1775 -550);
FORCEPROP 1 LAST PATH I21
J 0
(-1775 -550);
DISPLAY 0.723404 (-1775 -550);
PAINT GREEN (-1775 -550);
DISPLAY INVISIBLE (-1775 -550);
FORCEPROP 1 LAST PART_NUMBER BAM138K0003
J 0
(-1624 -636);
DISPLAY 0.723404 (-1624 -636);
PAINT GREEN (-1624 -636);
DISPLAY INVISIBLE (-1624 -636);
FORCEADD UNIVERSAL_GND..1
(-1725 -925);
FORCEPROP 3 LASTPIN (-1725 -875) SIG_NAME GND\g
J 0
(-1715 -865);
DISPLAY 0.659574 (-1715 -865);
PAINT MONO (-1715 -865);
DISPLAY INVISIBLE (-1715 -865);
FORCEPROP 2 LAST CDS_LIB pure_quanta_power
J 0
(-1725 -925);
DISPLAY INVISIBLE (-1725 -925);
FORCEPROP 1 LAST HDL_POWER GND
J 1
(-1700 -1000);
DISPLAY 0.872340 (-1700 -1000);
PAINT GREEN (-1700 -1000);
DISPLAY INVISIBLE (-1700 -1000);
FORCEPROP 1 LAST PATH I22
J 0
(-1650 -925);
DISPLAY 0.872340 (-1650 -925);
PAINT AQUA (-1650 -925);
DISPLAY INVISIBLE (-1650 -925);
FORCEADD Q_RES..2
(-1725 -75);
FORCEPROP 1 LAST LOCATION R3435
J 0
(-1680 50);
DISPLAY 0.638298 (-1680 50);
FORCEPROP 2 LAST $SEC 1
J 0
(-1675 150);
DISPLAY 0.680851 (-1675 150);
PAINT MONO (-1675 150);
DISPLAY INVISIBLE (-1675 150);
FORCEPROP 2 LAST CDS_SEC 1
J 0
(-1675 150);
DISPLAY 1.021277 (-1675 150);
DISPLAY INVISIBLE (-1675 150);
FORCEPROP 1 LASTPIN (-1725 25) $PN 1
J 0
(-1720 -13);
DISPLAY 0.787234 (-1720 -13);
FORCEPROP 1 LASTPIN (-1725 -175) $PN 2
J 0
(-1720 -165);
DISPLAY 0.787234 (-1720 -165);
FORCEPROP 1 LAST WATTAGE 1/16W
J 0
(-1685 -100);
DISPLAY 0.638298 (-1685 -100);
FORCEPROP 1 LAST MATERIAL CHIP
J 0
(-1685 -150);
DISPLAY 0.638298 (-1685 -150);
FORCEPROP 1 LAST VALUE 4.7K
J 0
(-1680 0);
DISPLAY 0.638298 (-1680 0);
FORCEPROP 1 LAST TOLERANCE 5%
J 0
(-1680 -50);
DISPLAY 0.638298 (-1680 -50);
FORCEPROP 1 LAST PACK_TYPE 0402LF
J 0
(-1685 -200);
DISPLAY 0.638298 (-1685 -200);
FORCEPROP 2 LAST CDS_LIB pure_quanta
J 0
(-1725 -75);
PAINT MONO (-1725 -75);
DISPLAY INVISIBLE (-1725 -75);
FORCEPROP 1 LAST PATH I23
J 0
(-1675 100);
DISPLAY 0.978723 (-1675 100);
PAINT WHITE (-1675 100);
DISPLAY INVISIBLE (-1675 100);
FORCEPROP 1 LAST PART_NUMBER CS24702JB10
J 0
(-1685 -250);
DISPLAY 0.638298 (-1685 -250);
DISPLAY INVISIBLE (-1685 -250);
FORCEADD UNIVERSAL_POWER..1
(-1725 225);
FORCEPROP 3 LASTPIN (-1725 175) SIG_NAME P3V3_AUX\g
J 0
(-1715 185);
DISPLAY 0.659574 (-1715 185);
PAINT MONO (-1715 185);
DISPLAY INVISIBLE (-1715 185);
FORCEPROP 1 LAST HDL_POWER P3V3_AUX
J 1
(-1725 275);
DISPLAY 0.872340 (-1725 275);
PAINT GREEN (-1725 275);
FORCEPROP 2 LAST CDS_LIB pure_quanta_power
J 0
(-1725 225);
PAINT MONO (-1725 225);
DISPLAY INVISIBLE (-1725 225);
FORCEPROP 1 LAST PATH I24
J 0
(-1675 250);
DISPLAY 0.872340 (-1675 250);
PAINT AQUA (-1675 250);
DISPLAY INVISIBLE (-1675 250);
FORCEADD UNIVERSAL_GND..1
(-800 -650);
FORCEPROP 3 LASTPIN (-800 -600) SIG_NAME GND\g
J 0
(-790 -590);
DISPLAY 0.659574 (-790 -590);
PAINT MONO (-790 -590);
DISPLAY INVISIBLE (-790 -590);
FORCEPROP 2 LAST CDS_LIB pure_quanta_power
J 0
(-800 -650);
DISPLAY INVISIBLE (-800 -650);
FORCEPROP 1 LAST HDL_POWER GND
J 1
(-775 -725);
DISPLAY 0.872340 (-775 -725);
PAINT GREEN (-775 -725);
DISPLAY INVISIBLE (-775 -725);
FORCEPROP 1 LAST PATH I25
J 0
(-725 -650);
DISPLAY 0.872340 (-725 -650);
PAINT AQUA (-725 -650);
DISPLAY INVISIBLE (-725 -650);
FORCEADD MOSFET_NCH_DUAL..2
(-850 -275);
FORCEPROP 1 LAST LOCATION Q104
J 0
(-699 -299);
DISPLAY 0.723404 (-699 -299);
PAINT GREEN (-699 -299);
FORCEPROP 0 LAST $SEC 2
J 0
(-675 -150);
DISPLAY 0.680851 (-675 -150);
PAINT MONO (-675 -150);
DISPLAY INVISIBLE (-675 -150);
FORCEPROP 0 LAST CDS_SEC 2
J 0
(-675 -150);
DISPLAY 1.021277 (-675 -150);
DISPLAY INVISIBLE (-675 -150);
FORCEPROP 0 LASTPIN (-800 -75) $PN 3
R 1
J 0
(-810 -65);
DISPLAY 0.680851 (-810 -65);
PAINT MONO (-810 -65);
FORCEPROP 0 LASTPIN (-1050 -325) $PN 5
J 2
(-1060 -315);
DISPLAY 0.680851 (-1060 -315);
PAINT MONO (-1060 -315);
FORCEPROP 0 LASTPIN (-800 -475) $PN 4
R 1
J 2
(-810 -485);
DISPLAY 0.680851 (-810 -485);
PAINT MONO (-810 -485);
FORCEPROP 2 LAST VALUE PJT138K
J 0
(-675 -250);
DISPLAY 1.021277 (-675 -250);
FORCEPROP 2 LAST PART_TYPE SMLF
J 0
(-675 -200);
DISPLAY 1.021277 (-675 -200);
FORCEPROP 1 LAST MATERIAL IC
J 0
(-699 -424);
DISPLAY 0.723404 (-699 -424);
PAINT GREEN (-699 -424);
FORCEPROP 1 LAST CDS_LMAN_SYM_OUTLINE -150,150,150,-150
J 0
(-850 -275);
DISPLAY 0.468085 (-850 -275);
PAINT GREEN (-850 -275);
DISPLAY INVISIBLE (-850 -275);
FORCEPROP 1 LAST NEEDS_NO_SIZE TRUE
J 0
(-700 -384);
DISPLAY 0.468085 (-700 -384);
PAINT GREEN (-700 -384);
DISPLAY INVISIBLE (-700 -384);
FORCEPROP 2 LAST CDS_LIB pure_quanta
J 0
(-850 -275);
DISPLAY INVISIBLE (-850 -275);
FORCEPROP 1 LAST PATH I26
J 0
(-700 -425);
DISPLAY 0.723404 (-700 -425);
PAINT GREEN (-700 -425);
DISPLAY INVISIBLE (-700 -425);
FORCEPROP 1 LAST PART_NUMBER BAM138K0003
J 0
(-699 -369);
DISPLAY 0.723404 (-699 -369);
PAINT GREEN (-699 -369);
DISPLAY INVISIBLE (-699 -369);
FORCEADD Q_RES..2
(-800 175);
FORCEPROP 1 LAST LOCATION R3437
J 0
(-755 300);
DISPLAY 0.978723 (-755 300);
FORCEPROP 0 LAST $SEC 1
J 0
(-750 350);
DISPLAY 0.680851 (-750 350);
PAINT MONO (-750 350);
DISPLAY INVISIBLE (-750 350);
FORCEPROP 0 LAST CDS_SEC 1
J 0
(-750 350);
DISPLAY 1.021277 (-750 350);
DISPLAY INVISIBLE (-750 350);
FORCEPROP 1 LASTPIN (-800 275) $PN 1
J 0
(-795 237);
DISPLAY 0.787234 (-795 237);
PAINT MONO (-795 237);
FORCEPROP 1 LASTPIN (-800 75) $PN 2
J 0
(-795 85);
DISPLAY 0.787234 (-795 85);
PAINT MONO (-795 85);
FORCEPROP 1 LAST TOLERANCE 1%
J 0
(-755 200);
DISPLAY 0.638298 (-755 200);
FORCEPROP 1 LAST VALUE 100K
J 0
(-755 250);
DISPLAY 0.638298 (-755 250);
FORCEPROP 1 LAST MATERIAL CHIP
J 0
(-760 100);
DISPLAY 0.638298 (-760 100);
FORCEPROP 1 LAST WATTAGE 1/16W
J 0
(-760 150);
DISPLAY 0.638298 (-760 150);
FORCEPROP 1 LAST PACK_TYPE 0402LF
J 0
(-760 50);
DISPLAY 0.638298 (-760 50);
FORCEPROP 2 LAST CDS_LIB pure_quanta
J 0
(-800 175);
DISPLAY INVISIBLE (-800 175);
FORCEPROP 1 LAST PATH I27
J 0
(-750 350);
DISPLAY 0.978723 (-750 350);
PAINT WHITE (-750 350);
DISPLAY INVISIBLE (-750 350);
FORCEPROP 1 LAST PART_NUMBER CS41002FB09
J 0
(-760 0);
DISPLAY 0.638298 (-760 0);
DISPLAY INVISIBLE (-760 0);
FORCEADD UNIVERSAL_POWER..1
(-800 475);
FORCEPROP 3 LASTPIN (-800 425) SIG_NAME P3V3_AUX\g
J 0
(-790 435);
DISPLAY 0.659574 (-790 435);
PAINT MONO (-790 435);
DISPLAY INVISIBLE (-790 435);
FORCEPROP 1 LAST HDL_POWER P3V3_AUX
J 1
(-800 525);
DISPLAY 0.872340 (-800 525);
PAINT GREEN (-800 525);
FORCEPROP 2 LAST CDS_LIB pure_quanta_power
J 0
(-800 475);
DISPLAY INVISIBLE (-800 475);
FORCEPROP 1 LAST PATH I28
J 0
(-750 500);
DISPLAY 0.872340 (-750 500);
PAINT AQUA (-750 500);
DISPLAY INVISIBLE (-750 500);
FORCEADD UNIVERSAL_GND..1
(100 -650);
FORCEPROP 3 LASTPIN (100 -600) SIG_NAME GND\g
J 0
(110 -590);
DISPLAY 0.659574 (110 -590);
PAINT MONO (110 -590);
DISPLAY INVISIBLE (110 -590);
FORCEPROP 2 LAST CDS_LIB pure_quanta_power
J 0
(100 -650);
DISPLAY INVISIBLE (100 -650);
FORCEPROP 1 LAST HDL_POWER GND
J 1
(125 -725);
DISPLAY 0.872340 (125 -725);
PAINT GREEN (125 -725);
DISPLAY INVISIBLE (125 -725);
FORCEPROP 1 LAST PATH I29
J 0
(175 -650);
DISPLAY 0.872340 (175 -650);
PAINT AQUA (175 -650);
DISPLAY INVISIBLE (175 -650);
FORCEADD Q_RES..2
(-2950 -800);
FORCEPROP 1 LAST LOCATION R3430
J 0
(-2905 -675);
DISPLAY 0.978723 (-2905 -675);
FORCEPROP 0 LAST $SEC 1
J 0
(-2900 -625);
DISPLAY 0.680851 (-2900 -625);
PAINT MONO (-2900 -625);
DISPLAY INVISIBLE (-2900 -625);
FORCEPROP 0 LAST CDS_SEC 1
J 0
(-2900 -625);
DISPLAY 1.021277 (-2900 -625);
DISPLAY INVISIBLE (-2900 -625);
FORCEPROP 1 LASTPIN (-2950 -700) $PN 1
J 0
(-2945 -738);
DISPLAY 0.787234 (-2945 -738);
PAINT MONO (-2945 -738);
FORCEPROP 1 LASTPIN (-2950 -900) $PN 2
J 0
(-2945 -890);
DISPLAY 0.787234 (-2945 -890);
PAINT MONO (-2945 -890);
FORCEPROP 1 LAST MATERIAL EMPTY
J 0
(-2910 -875);
DISPLAY 0.510638 (-2910 -875);
FORCEPROP 1 LAST WATTAGE 1/16W
J 0
(-2910 -825);
DISPLAY 0.510638 (-2910 -825);
FORCEPROP 1 LAST TOLERANCE 1%
J 0
(-2905 -775);
DISPLAY 0.510638 (-2905 -775);
FORCEPROP 1 LAST VALUE 100K
J 0
(-2905 -725);
DISPLAY 0.510638 (-2905 -725);
FORCEPROP 1 LAST PACK_TYPE 0402LF
J 0
(-2910 -975);
DISPLAY 0.510638 (-2910 -975);
FORCEPROP 2 LAST CDS_LIB pure_quanta
J 0
(-2950 -800);
DISPLAY INVISIBLE (-2950 -800);
FORCEPROP 1 LAST PATH I3
J 0
(-2900 -625);
DISPLAY 0.978723 (-2900 -625);
PAINT WHITE (-2900 -625);
DISPLAY INVISIBLE (-2900 -625);
FORCEPROP 1 LAST PART_NUMBER CS41002FB09
J 0
(-2910 -925);
DISPLAY 0.510638 (-2910 -925);
DISPLAY INVISIBLE (-2910 -925);
FORCEADD Q_CAP..1
(100 -450);
FORCEPROP 1 LAST LOCATION C1976
J 0
(150 -350);
DISPLAY 0.638298 (150 -350);
FORCEPROP 2 LAST $SEC 1
J 0
(150 -250);
DISPLAY 0.680851 (150 -250);
PAINT MONO (150 -250);
DISPLAY INVISIBLE (150 -250);
FORCEPROP 2 LAST CDS_SEC 1
J 0
(150 -250);
DISPLAY 1.021277 (150 -250);
DISPLAY INVISIBLE (150 -250);
FORCEPROP 1 LASTPIN (100 -350) $PN 1
J 0
(110 -370);
DISPLAY 0.787234 (110 -370);
PAINT MONO (110 -370);
FORCEPROP 1 LASTPIN (100 -550) $PN 2
J 0
(110 -570);
DISPLAY 0.787234 (110 -570);
PAINT MONO (110 -570);
FORCEPROP 1 LAST PACK_TYPE 0402
J 0
(150 -650);
DISPLAY 0.638298 (150 -650);
FORCEPROP 1 LAST MATERIAL X7R
J 0
(150 -550);
DISPLAY 0.638298 (150 -550);
PAINT RED (150 -550);
FORCEPROP 1 LAST TOLERANCE 10%
J 0
(150 -500);
DISPLAY 0.638298 (150 -500);
FORCEPROP 1 LAST VALUE 0.1UF
J 0
(150 -400);
DISPLAY 0.638298 (150 -400);
FORCEPROP 1 LAST VOLTAGE 25V
J 0
(150 -450);
DISPLAY 0.638298 (150 -450);
FORCEPROP 2 LAST CDS_LIB pure_quanta
J 0
(100 -450);
DISPLAY INVISIBLE (100 -450);
FORCEPROP 1 LAST PATH I30
J 0
(150 -300);
DISPLAY 0.978723 (150 -300);
PAINT WHITE (150 -300);
DISPLAY INVISIBLE (150 -300);
FORCEPROP 1 LAST PART_NUMBER CH4104K1B00
J 0
(150 -600);
DISPLAY 0.638298 (150 -600);
DISPLAY INVISIBLE (150 -600);
FORCEADD OFFPAGE..2
(375 -50);
FORCEPROP 2 LAST $XR0 81 
J 0
(564 -50);
DISPLAY 0.638298 (564 -50);
PAINT MONO (564 -50);
FORCEPROP 2 LAST CDS_LIB standard
J 0
(375 -50);
DISPLAY INVISIBLE (375 -50);
FORCEPROP 1 LAST OFFPAGE TRUE
J 0
(700 -175);
DISPLAY 0.872340 (700 -175);
PAINT AQUA (700 -175);
DISPLAY INVISIBLE (700 -175);
FORCEPROP 1 LAST COMMENT_BODY TRUE
J 0
(330 -145);
DISPLAY 0.872340 (330 -145);
PAINT GREEN (330 -145);
DISPLAY INVISIBLE (330 -145);
FORCEPROP 2 LAST PATH I31
J 0
(575 0);
DISPLAY 1.021277 (575 0);
DISPLAY INVISIBLE (575 0);
FORCEADD MOSFET_NCH_DUAL..1
(-1800 1025);
FORCEPROP 1 LAST LOCATION Q103
J 0
(-1649 999);
DISPLAY 0.723404 (-1649 999);
PAINT GREEN (-1649 999);
FORCEPROP 0 LAST $SEC 1
J 0
(-1625 1150);
DISPLAY 0.680851 (-1625 1150);
PAINT MONO (-1625 1150);
DISPLAY INVISIBLE (-1625 1150);
FORCEPROP 2 LAST CDS_SEC 1
J 0
(-1625 1150);
DISPLAY 1.021277 (-1625 1150);
DISPLAY INVISIBLE (-1625 1150);
FORCEPROP 0 LASTPIN (-1750 1225) $PN 6
R 1
J 0
(-1760 1235);
DISPLAY 0.680851 (-1760 1235);
PAINT MONO (-1760 1235);
FORCEPROP 0 LASTPIN (-2000 975) $PN 2
J 2
(-2010 985);
DISPLAY 0.680851 (-2010 985);
PAINT MONO (-2010 985);
FORCEPROP 0 LASTPIN (-1750 825) $PN 1
R 1
J 2
(-1760 815);
DISPLAY 0.680851 (-1760 815);
PAINT MONO (-1760 815);
FORCEPROP 2 LAST PART_TYPE SMLF
J 0
(-1625 1100);
DISPLAY 1.021277 (-1625 1100);
FORCEPROP 2 LAST VALUE PJT138K
J 0
(-1625 1050);
DISPLAY 1.021277 (-1625 1050);
FORCEPROP 1 LAST MATERIAL IC
J 0
(-1649 874);
DISPLAY 0.723404 (-1649 874);
PAINT GREEN (-1649 874);
FORCEPROP 2 LAST CDS_LIB pure_quanta
J 0
(-1800 1025);
DISPLAY INVISIBLE (-1800 1025);
FORCEPROP 1 LAST NEEDS_NO_SIZE TRUE
J 0
(-1800 1024);
DISPLAY 0.468085 (-1800 1024);
PAINT GREEN (-1800 1024);
DISPLAY INVISIBLE (-1800 1024);
FORCEPROP 1 LAST CDS_LMAN_SYM_OUTLINE -150,150,150,-150
J 0
(-1800 1025);
DISPLAY 0.468085 (-1800 1025);
PAINT GREEN (-1800 1025);
DISPLAY INVISIBLE (-1800 1025);
FORCEPROP 1 LAST PATH I37
J 0
(-1800 1025);
DISPLAY 0.723404 (-1800 1025);
PAINT GREEN (-1800 1025);
DISPLAY INVISIBLE (-1800 1025);
FORCEPROP 1 LAST PART_NUMBER BAM138K0003
J 0
(-1649 939);
DISPLAY 0.723404 (-1649 939);
PAINT GREEN (-1649 939);
DISPLAY INVISIBLE (-1649 939);
FORCEADD UNIVERSAL_GND..1
(-1750 650);
FORCEPROP 3 LASTPIN (-1750 700) SIG_NAME GND\g
J 0
(-1740 710);
DISPLAY 0.659574 (-1740 710);
PAINT MONO (-1740 710);
DISPLAY INVISIBLE (-1740 710);
FORCEPROP 2 LAST CDS_LIB pure_quanta_power
J 0
(-1750 650);
DISPLAY INVISIBLE (-1750 650);
FORCEPROP 1 LAST HDL_POWER GND
J 1
(-1725 575);
DISPLAY 0.872340 (-1725 575);
PAINT GREEN (-1725 575);
DISPLAY INVISIBLE (-1725 575);
FORCEPROP 1 LAST PATH I38
J 0
(-1675 650);
DISPLAY 0.872340 (-1675 650);
PAINT AQUA (-1675 650);
DISPLAY INVISIBLE (-1675 650);
FORCEADD Q_RES..2
(-1750 1475);
FORCEPROP 1 LAST LOCATION R3434
J 0
(-1705 1600);
DISPLAY 0.638298 (-1705 1600);
FORCEPROP 2 LAST $SEC 1
J 0
(-1700 1700);
DISPLAY 0.680851 (-1700 1700);
PAINT MONO (-1700 1700);
DISPLAY INVISIBLE (-1700 1700);
FORCEPROP 2 LAST CDS_SEC 1
J 0
(-1700 1700);
DISPLAY 1.021277 (-1700 1700);
DISPLAY INVISIBLE (-1700 1700);
FORCEPROP 1 LASTPIN (-1750 1575) $PN 1
J 0
(-1745 1537);
DISPLAY 0.787234 (-1745 1537);
FORCEPROP 1 LASTPIN (-1750 1375) $PN 2
J 0
(-1745 1385);
DISPLAY 0.787234 (-1745 1385);
FORCEPROP 1 LAST VALUE 4.7K
J 0
(-1705 1550);
DISPLAY 0.638298 (-1705 1550);
FORCEPROP 1 LAST TOLERANCE 5%
J 0
(-1705 1500);
DISPLAY 0.638298 (-1705 1500);
FORCEPROP 1 LAST PACK_TYPE 0402LF
J 0
(-1710 1350);
DISPLAY 0.638298 (-1710 1350);
FORCEPROP 1 LAST MATERIAL CHIP
J 0
(-1710 1400);
DISPLAY 0.638298 (-1710 1400);
FORCEPROP 1 LAST WATTAGE 1/16W
J 0
(-1710 1450);
DISPLAY 0.638298 (-1710 1450);
FORCEPROP 2 LAST CDS_LIB pure_quanta
J 0
(-1750 1475);
PAINT MONO (-1750 1475);
DISPLAY INVISIBLE (-1750 1475);
FORCEPROP 1 LAST PATH I39
J 0
(-1700 1650);
DISPLAY 0.978723 (-1700 1650);
PAINT WHITE (-1700 1650);
DISPLAY INVISIBLE (-1700 1650);
FORCEPROP 1 LAST PART_NUMBER CS24702JB10
J 0
(-1710 1300);
DISPLAY 0.638298 (-1710 1300);
DISPLAY INVISIBLE (-1710 1300);
FORCEADD MOSFET_NCH_DUAL..1
(-1800 2375);
FORCEPROP 1 LAST LOCATION Q102
J 0
(-1649 2349);
DISPLAY 0.723404 (-1649 2349);
PAINT GREEN (-1649 2349);
FORCEPROP 0 LAST $SEC 1
J 0
(-1625 2500);
DISPLAY 0.680851 (-1625 2500);
PAINT MONO (-1625 2500);
DISPLAY INVISIBLE (-1625 2500);
FORCEPROP 0 LAST CDS_SEC 1
J 0
(-1625 2500);
DISPLAY 1.021277 (-1625 2500);
DISPLAY INVISIBLE (-1625 2500);
FORCEPROP 0 LASTPIN (-1750 2575) $PN 6
R 1
J 0
(-1760 2585);
DISPLAY 0.680851 (-1760 2585);
PAINT MONO (-1760 2585);
FORCEPROP 0 LASTPIN (-2000 2325) $PN 2
J 2
(-2010 2335);
DISPLAY 0.680851 (-2010 2335);
PAINT MONO (-2010 2335);
FORCEPROP 0 LASTPIN (-1750 2175) $PN 1
R 1
J 2
(-1760 2165);
DISPLAY 0.680851 (-1760 2165);
PAINT MONO (-1760 2165);
FORCEPROP 2 LAST VALUE PJT138K
J 0
(-1625 2400);
DISPLAY 1.021277 (-1625 2400);
FORCEPROP 1 LAST MATERIAL IC
J 0
(-1649 2224);
DISPLAY 0.723404 (-1649 2224);
PAINT GREEN (-1649 2224);
FORCEPROP 2 LAST PART_TYPE SMLF
J 0
(-1625 2450);
DISPLAY 1.021277 (-1625 2450);
FORCEPROP 1 LAST CDS_LMAN_SYM_OUTLINE -150,150,150,-150
J 0
(-1800 2375);
DISPLAY 0.468085 (-1800 2375);
PAINT GREEN (-1800 2375);
DISPLAY INVISIBLE (-1800 2375);
FORCEPROP 1 LAST NEEDS_NO_SIZE TRUE
J 0
(-1800 2374);
DISPLAY 0.468085 (-1800 2374);
PAINT GREEN (-1800 2374);
DISPLAY INVISIBLE (-1800 2374);
FORCEPROP 2 LAST CDS_LIB pure_quanta
J 0
(-1800 2375);
DISPLAY INVISIBLE (-1800 2375);
FORCEPROP 1 LAST PATH I40
J 0
(-1800 2375);
DISPLAY 0.723404 (-1800 2375);
PAINT GREEN (-1800 2375);
DISPLAY INVISIBLE (-1800 2375);
FORCEPROP 1 LAST PART_NUMBER BAM138K0003
J 0
(-1649 2289);
DISPLAY 0.723404 (-1649 2289);
PAINT GREEN (-1649 2289);
DISPLAY INVISIBLE (-1649 2289);
FORCEADD UNIVERSAL_POWER..1
(-1750 1775);
FORCEPROP 3 LASTPIN (-1750 1725) SIG_NAME P3V3_AUX\g
J 0
(-1740 1735);
DISPLAY 0.659574 (-1740 1735);
PAINT MONO (-1740 1735);
DISPLAY INVISIBLE (-1740 1735);
FORCEPROP 1 LAST HDL_POWER P3V3_AUX
J 1
(-1750 1825);
DISPLAY 0.872340 (-1750 1825);
PAINT GREEN (-1750 1825);
FORCEPROP 2 LAST CDS_LIB pure_quanta_power
J 0
(-1750 1775);
PAINT MONO (-1750 1775);
DISPLAY INVISIBLE (-1750 1775);
FORCEPROP 1 LAST PATH I41
J 0
(-1700 1800);
DISPLAY 0.872340 (-1700 1800);
PAINT AQUA (-1700 1800);
DISPLAY INVISIBLE (-1700 1800);
FORCEADD UNIVERSAL_GND..1
(-1750 2000);
FORCEPROP 3 LASTPIN (-1750 2050) SIG_NAME GND\g
J 0
(-1740 2060);
DISPLAY 0.659574 (-1740 2060);
PAINT MONO (-1740 2060);
DISPLAY INVISIBLE (-1740 2060);
FORCEPROP 2 LAST CDS_LIB pure_quanta_power
J 0
(-1750 2000);
DISPLAY INVISIBLE (-1750 2000);
FORCEPROP 1 LAST HDL_POWER GND
J 1
(-1725 1925);
DISPLAY 0.872340 (-1725 1925);
PAINT GREEN (-1725 1925);
DISPLAY INVISIBLE (-1725 1925);
FORCEPROP 1 LAST PATH I42
J 0
(-1675 2000);
DISPLAY 0.872340 (-1675 2000);
PAINT AQUA (-1675 2000);
DISPLAY INVISIBLE (-1675 2000);
FORCEADD MOSFET_NCH_DUAL..2
(-850 1300);
FORCEPROP 1 LAST LOCATION Q103
J 0
(-699 1276);
DISPLAY 0.723404 (-699 1276);
PAINT GREEN (-699 1276);
FORCEPROP 0 LAST $SEC 2
J 0
(-675 1425);
DISPLAY 0.680851 (-675 1425);
PAINT MONO (-675 1425);
DISPLAY INVISIBLE (-675 1425);
FORCEPROP 0 LAST CDS_SEC 2
J 0
(-675 1425);
DISPLAY 1.021277 (-675 1425);
DISPLAY INVISIBLE (-675 1425);
FORCEPROP 0 LASTPIN (-800 1500) $PN 3
R 1
J 0
(-810 1510);
DISPLAY 0.680851 (-810 1510);
PAINT MONO (-810 1510);
FORCEPROP 0 LASTPIN (-1050 1250) $PN 5
J 2
(-1060 1260);
DISPLAY 0.680851 (-1060 1260);
PAINT MONO (-1060 1260);
FORCEPROP 0 LASTPIN (-800 1100) $PN 4
R 1
J 2
(-810 1090);
DISPLAY 0.680851 (-810 1090);
PAINT MONO (-810 1090);
FORCEPROP 2 LAST VALUE PJT138K
J 0
(-675 1325);
DISPLAY 1.021277 (-675 1325);
FORCEPROP 1 LAST MATERIAL IC
J 0
(-699 1151);
DISPLAY 0.723404 (-699 1151);
PAINT GREEN (-699 1151);
FORCEPROP 2 LAST PART_TYPE SMLF
J 0
(-675 1375);
DISPLAY 1.021277 (-675 1375);
FORCEPROP 1 LAST CDS_LMAN_SYM_OUTLINE -150,150,150,-150
J 0
(-850 1300);
DISPLAY 0.468085 (-850 1300);
PAINT GREEN (-850 1300);
DISPLAY INVISIBLE (-850 1300);
FORCEPROP 1 LAST NEEDS_NO_SIZE TRUE
J 0
(-700 1191);
DISPLAY 0.468085 (-700 1191);
PAINT GREEN (-700 1191);
DISPLAY INVISIBLE (-700 1191);
FORCEPROP 2 LAST CDS_LIB pure_quanta
J 0
(-850 1300);
DISPLAY INVISIBLE (-850 1300);
FORCEPROP 1 LAST PATH I43
J 0
(-700 1150);
DISPLAY 0.723404 (-700 1150);
PAINT GREEN (-700 1150);
DISPLAY INVISIBLE (-700 1150);
FORCEPROP 1 LAST PART_NUMBER BAM138K0003
J 0
(-699 1206);
DISPLAY 0.723404 (-699 1206);
PAINT GREEN (-699 1206);
DISPLAY INVISIBLE (-699 1206);
FORCEADD UNIVERSAL_GND..1
(-800 925);
FORCEPROP 3 LASTPIN (-800 975) SIG_NAME GND\g
J 0
(-790 985);
DISPLAY 0.659574 (-790 985);
PAINT MONO (-790 985);
DISPLAY INVISIBLE (-790 985);
FORCEPROP 2 LAST CDS_LIB pure_quanta_power
J 0
(-800 925);
DISPLAY INVISIBLE (-800 925);
FORCEPROP 1 LAST HDL_POWER GND
J 1
(-775 850);
DISPLAY 0.872340 (-775 850);
PAINT GREEN (-775 850);
DISPLAY INVISIBLE (-775 850);
FORCEPROP 1 LAST PATH I44
J 0
(-725 925);
DISPLAY 0.872340 (-725 925);
PAINT AQUA (-725 925);
DISPLAY INVISIBLE (-725 925);
FORCEADD Q_RES..2
(-800 1725);
FORCEPROP 1 LAST LOCATION R3436
J 0
(-755 1850);
DISPLAY 0.978723 (-755 1850);
FORCEPROP 0 LAST $SEC 1
J 0
(-750 1900);
DISPLAY 0.680851 (-750 1900);
PAINT MONO (-750 1900);
DISPLAY INVISIBLE (-750 1900);
FORCEPROP 0 LAST CDS_SEC 1
J 0
(-750 1900);
DISPLAY 1.021277 (-750 1900);
DISPLAY INVISIBLE (-750 1900);
FORCEPROP 1 LASTPIN (-800 1825) $PN 1
J 0
(-795 1787);
DISPLAY 0.787234 (-795 1787);
PAINT MONO (-795 1787);
FORCEPROP 1 LASTPIN (-800 1625) $PN 2
J 0
(-795 1635);
DISPLAY 0.787234 (-795 1635);
PAINT MONO (-795 1635);
FORCEPROP 1 LAST TOLERANCE 1%
J 0
(-755 1750);
DISPLAY 0.638298 (-755 1750);
FORCEPROP 1 LAST VALUE 100K
J 0
(-755 1800);
DISPLAY 0.638298 (-755 1800);
FORCEPROP 1 LAST MATERIAL CHIP
J 0
(-760 1650);
DISPLAY 0.638298 (-760 1650);
FORCEPROP 1 LAST PACK_TYPE 0402LF
J 0
(-760 1600);
DISPLAY 0.638298 (-760 1600);
FORCEPROP 1 LAST WATTAGE 1/16W
J 0
(-760 1700);
DISPLAY 0.638298 (-760 1700);
FORCEPROP 2 LAST CDS_LIB pure_quanta
J 0
(-800 1725);
DISPLAY INVISIBLE (-800 1725);
FORCEPROP 1 LAST PATH I45
J 0
(-750 1900);
DISPLAY 0.978723 (-750 1900);
PAINT WHITE (-750 1900);
DISPLAY INVISIBLE (-750 1900);
FORCEPROP 1 LAST PART_NUMBER CS41002FB09
J 0
(-760 1550);
DISPLAY 0.638298 (-760 1550);
DISPLAY INVISIBLE (-760 1550);
FORCEADD UNIVERSAL_POWER..1
(-800 2025);
FORCEPROP 3 LASTPIN (-800 1975) SIG_NAME P3V3_AUX\g
J 0
(-790 1985);
DISPLAY 0.659574 (-790 1985);
PAINT MONO (-790 1985);
DISPLAY INVISIBLE (-790 1985);
FORCEPROP 1 LAST HDL_POWER P3V3_AUX
J 1
(-800 2075);
DISPLAY 0.872340 (-800 2075);
PAINT GREEN (-800 2075);
FORCEPROP 2 LAST CDS_LIB pure_quanta_power
J 0
(-800 2025);
DISPLAY INVISIBLE (-800 2025);
FORCEPROP 1 LAST PATH I46
J 0
(-750 2050);
DISPLAY 0.872340 (-750 2050);
PAINT AQUA (-750 2050);
DISPLAY INVISIBLE (-750 2050);
FORCEADD UNIVERSAL_GND..1
(-775 2300);
FORCEPROP 3 LASTPIN (-775 2350) SIG_NAME GND\g
J 0
(-765 2360);
DISPLAY 0.659574 (-765 2360);
PAINT MONO (-765 2360);
DISPLAY INVISIBLE (-765 2360);
FORCEPROP 2 LAST CDS_LIB pure_quanta_power
J 0
(-775 2300);
DISPLAY INVISIBLE (-775 2300);
FORCEPROP 1 LAST HDL_POWER GND
J 1
(-750 2225);
DISPLAY 0.872340 (-750 2225);
PAINT GREEN (-750 2225);
DISPLAY INVISIBLE (-750 2225);
FORCEPROP 1 LAST PATH I47
J 0
(-700 2300);
DISPLAY 0.872340 (-700 2300);
PAINT AQUA (-700 2300);
DISPLAY INVISIBLE (-700 2300);
FORCEADD MOSFET_NCH_DUAL..2
(-825 2675);
FORCEPROP 1 LAST LOCATION Q102
J 0
(-674 2651);
DISPLAY 0.723404 (-674 2651);
PAINT GREEN (-674 2651);
FORCEPROP 0 LAST $SEC 2
J 0
(-650 2800);
DISPLAY 0.680851 (-650 2800);
PAINT MONO (-650 2800);
DISPLAY INVISIBLE (-650 2800);
FORCEPROP 0 LAST CDS_SEC 2
J 0
(-650 2800);
DISPLAY 1.021277 (-650 2800);
DISPLAY INVISIBLE (-650 2800);
FORCEPROP 0 LASTPIN (-775 2875) $PN 3
R 1
J 0
(-785 2885);
DISPLAY 0.680851 (-785 2885);
PAINT MONO (-785 2885);
FORCEPROP 0 LASTPIN (-1025 2625) $PN 5
J 2
(-1035 2635);
DISPLAY 0.680851 (-1035 2635);
PAINT MONO (-1035 2635);
FORCEPROP 0 LASTPIN (-775 2475) $PN 4
R 1
J 2
(-785 2465);
DISPLAY 0.680851 (-785 2465);
PAINT MONO (-785 2465);
FORCEPROP 1 LAST MATERIAL IC
J 0
(-674 2526);
DISPLAY 0.723404 (-674 2526);
PAINT GREEN (-674 2526);
FORCEPROP 2 LAST VALUE PJT138K
J 0
(-650 2700);
DISPLAY 1.021277 (-650 2700);
FORCEPROP 2 LAST PART_TYPE SMLF
J 0
(-650 2750);
DISPLAY 1.021277 (-650 2750);
FORCEPROP 2 LAST CDS_LIB pure_quanta
J 0
(-825 2675);
DISPLAY INVISIBLE (-825 2675);
FORCEPROP 1 LAST NEEDS_NO_SIZE TRUE
J 0
(-675 2566);
DISPLAY 0.468085 (-675 2566);
PAINT GREEN (-675 2566);
DISPLAY INVISIBLE (-675 2566);
FORCEPROP 1 LAST CDS_LMAN_SYM_OUTLINE -150,150,150,-150
J 0
(-825 2675);
DISPLAY 0.468085 (-825 2675);
PAINT GREEN (-825 2675);
DISPLAY INVISIBLE (-825 2675);
FORCEPROP 1 LAST PATH I48
J 0
(-675 2525);
DISPLAY 0.723404 (-675 2525);
PAINT GREEN (-675 2525);
DISPLAY INVISIBLE (-675 2525);
FORCEPROP 1 LAST PART_NUMBER BAM138K0003
J 0
(-674 2581);
DISPLAY 0.723404 (-674 2581);
PAINT GREEN (-674 2581);
DISPLAY INVISIBLE (-674 2581);
FORCEADD Q_RES..2
(-1775 2825);
FORCEPROP 1 LAST LOCATION R3433
J 0
(-1730 2950);
DISPLAY 0.638298 (-1730 2950);
FORCEPROP 2 LAST $SEC 1
J 0
(-1725 3050);
DISPLAY 0.680851 (-1725 3050);
PAINT MONO (-1725 3050);
DISPLAY INVISIBLE (-1725 3050);
FORCEPROP 2 LAST CDS_SEC 1
J 0
(-1725 3050);
DISPLAY 1.021277 (-1725 3050);
DISPLAY INVISIBLE (-1725 3050);
FORCEPROP 1 LASTPIN (-1775 2925) $PN 1
J 0
(-1770 2887);
DISPLAY 0.787234 (-1770 2887);
FORCEPROP 1 LASTPIN (-1775 2725) $PN 2
J 0
(-1770 2735);
DISPLAY 0.787234 (-1770 2735);
FORCEPROP 1 LAST MATERIAL CHIP
J 0
(-1735 2750);
DISPLAY 0.638298 (-1735 2750);
FORCEPROP 1 LAST PACK_TYPE 0402LF
J 0
(-1735 2700);
DISPLAY 0.638298 (-1735 2700);
FORCEPROP 1 LAST WATTAGE 1/16W
J 0
(-1735 2800);
DISPLAY 0.638298 (-1735 2800);
FORCEPROP 1 LAST TOLERANCE 5%
J 0
(-1730 2850);
DISPLAY 0.638298 (-1730 2850);
FORCEPROP 1 LAST VALUE 4.7K
J 0
(-1730 2900);
DISPLAY 0.638298 (-1730 2900);
FORCEPROP 2 LAST CDS_LIB pure_quanta
J 0
(-1775 2825);
PAINT MONO (-1775 2825);
DISPLAY INVISIBLE (-1775 2825);
FORCEPROP 1 LAST PATH I49
J 0
(-1725 3000);
DISPLAY 0.978723 (-1725 3000);
PAINT WHITE (-1725 3000);
DISPLAY INVISIBLE (-1725 3000);
FORCEPROP 1 LAST PART_NUMBER CS24702JB10
J 0
(-1735 2650);
DISPLAY 0.638298 (-1735 2650);
DISPLAY INVISIBLE (-1735 2650);
FORCEADD UNIVERSAL_POWER..1
(-2975 -75);
FORCEPROP 3 LASTPIN (-2975 -125) SIG_NAME P3V3_AUX\g
J 0
(-2965 -115);
DISPLAY 0.659574 (-2965 -115);
PAINT MONO (-2965 -115);
DISPLAY INVISIBLE (-2965 -115);
FORCEPROP 1 LAST HDL_POWER P3V3_AUX
J 1
(-2975 -25);
DISPLAY 0.872340 (-2975 -25);
PAINT GREEN (-2975 -25);
FORCEPROP 2 LAST CDS_LIB pure_quanta_power
J 0
(-2975 -75);
PAINT MONO (-2975 -75);
DISPLAY INVISIBLE (-2975 -75);
FORCEPROP 1 LAST PATH I5
J 0
(-2925 -50);
DISPLAY 0.872340 (-2925 -50);
PAINT AQUA (-2925 -50);
DISPLAY INVISIBLE (-2925 -50);
FORCEADD UNIVERSAL_POWER..1
(-1775 3125);
FORCEPROP 3 LASTPIN (-1775 3075) SIG_NAME P3V3_AUX\g
J 0
(-1765 3085);
DISPLAY 0.659574 (-1765 3085);
PAINT MONO (-1765 3085);
DISPLAY INVISIBLE (-1765 3085);
FORCEPROP 1 LAST HDL_POWER P3V3_AUX
J 1
(-1775 3175);
DISPLAY 0.872340 (-1775 3175);
PAINT GREEN (-1775 3175);
FORCEPROP 2 LAST CDS_LIB pure_quanta_power
J 0
(-1775 3125);
PAINT MONO (-1775 3125);
DISPLAY INVISIBLE (-1775 3125);
FORCEPROP 1 LAST PATH I50
J 0
(-1725 3150);
DISPLAY 0.872340 (-1725 3150);
PAINT AQUA (-1725 3150);
DISPLAY INVISIBLE (-1725 3150);
FORCEADD UNIVERSAL_GND..1
(-1825 3400);
FORCEPROP 3 LASTPIN (-1825 3450) SIG_NAME GND\g
J 0
(-1815 3460);
DISPLAY 0.659574 (-1815 3460);
PAINT MONO (-1815 3460);
DISPLAY INVISIBLE (-1815 3460);
FORCEPROP 2 LAST CDS_LIB pure_quanta_power
J 0
(-1825 3400);
DISPLAY INVISIBLE (-1825 3400);
FORCEPROP 1 LAST HDL_POWER GND
J 1
(-1800 3325);
DISPLAY 0.872340 (-1800 3325);
PAINT GREEN (-1800 3325);
DISPLAY INVISIBLE (-1800 3325);
FORCEPROP 1 LAST PATH I51
J 0
(-1750 3400);
DISPLAY 0.872340 (-1750 3400);
PAINT AQUA (-1750 3400);
DISPLAY INVISIBLE (-1750 3400);
FORCEADD MOSFET_NCH_DUAL..1
(-1875 3775);
FORCEPROP 1 LAST LOCATION Q101
J 0
(-1724 3749);
DISPLAY 0.723404 (-1724 3749);
PAINT GREEN (-1724 3749);
FORCEPROP 0 LAST $SEC 1
J 0
(-1700 3900);
DISPLAY 0.680851 (-1700 3900);
PAINT MONO (-1700 3900);
DISPLAY INVISIBLE (-1700 3900);
FORCEPROP 2 LAST CDS_SEC 1
J 0
(-1700 3900);
DISPLAY 1.021277 (-1700 3900);
DISPLAY INVISIBLE (-1700 3900);
FORCEPROP 0 LASTPIN (-1825 3975) $PN 6
R 1
J 0
(-1835 3985);
DISPLAY 0.680851 (-1835 3985);
PAINT MONO (-1835 3985);
FORCEPROP 0 LASTPIN (-2075 3725) $PN 2
J 2
(-2085 3735);
DISPLAY 0.680851 (-2085 3735);
PAINT MONO (-2085 3735);
FORCEPROP 0 LASTPIN (-1825 3575) $PN 1
R 1
J 2
(-1835 3565);
DISPLAY 0.680851 (-1835 3565);
PAINT MONO (-1835 3565);
FORCEPROP 1 LAST MATERIAL IC
J 0
(-1724 3624);
DISPLAY 0.723404 (-1724 3624);
PAINT GREEN (-1724 3624);
FORCEPROP 2 LAST PART_TYPE SMLF
J 0
(-1700 3850);
DISPLAY 1.021277 (-1700 3850);
FORCEPROP 2 LAST VALUE PJT138K
J 0
(-1700 3800);
DISPLAY 1.021277 (-1700 3800);
FORCEPROP 1 LAST CDS_LMAN_SYM_OUTLINE -150,150,150,-150
J 0
(-1875 3775);
DISPLAY 0.468085 (-1875 3775);
PAINT GREEN (-1875 3775);
DISPLAY INVISIBLE (-1875 3775);
FORCEPROP 1 LAST NEEDS_NO_SIZE TRUE
J 0
(-1875 3774);
DISPLAY 0.468085 (-1875 3774);
PAINT GREEN (-1875 3774);
DISPLAY INVISIBLE (-1875 3774);
FORCEPROP 2 LAST CDS_LIB pure_quanta
J 0
(-1875 3775);
DISPLAY INVISIBLE (-1875 3775);
FORCEPROP 1 LAST PATH I52
J 0
(-1875 3775);
DISPLAY 0.723404 (-1875 3775);
PAINT GREEN (-1875 3775);
DISPLAY INVISIBLE (-1875 3775);
FORCEPROP 1 LAST PART_NUMBER BAM138K0003
J 0
(-1724 3689);
DISPLAY 0.723404 (-1724 3689);
PAINT GREEN (-1724 3689);
DISPLAY INVISIBLE (-1724 3689);
FORCEADD Q_RES..2
(-1825 4375);
FORCEPROP 1 LAST LOCATION R3432
J 0
(-1780 4500);
DISPLAY 0.638298 (-1780 4500);
FORCEPROP 2 LAST $SEC 1
J 0
(-1775 4600);
DISPLAY 0.680851 (-1775 4600);
PAINT MONO (-1775 4600);
DISPLAY INVISIBLE (-1775 4600);
FORCEPROP 2 LAST CDS_SEC 1
J 0
(-1775 4600);
DISPLAY 1.021277 (-1775 4600);
DISPLAY INVISIBLE (-1775 4600);
FORCEPROP 1 LASTPIN (-1825 4475) $PN 1
J 0
(-1820 4437);
DISPLAY 0.787234 (-1820 4437);
FORCEPROP 1 LASTPIN (-1825 4275) $PN 2
J 0
(-1820 4285);
DISPLAY 0.787234 (-1820 4285);
FORCEPROP 1 LAST PACK_TYPE 0402LF
J 0
(-1785 4250);
DISPLAY 0.638298 (-1785 4250);
FORCEPROP 1 LAST TOLERANCE 5%
J 0
(-1780 4400);
DISPLAY 0.638298 (-1780 4400);
FORCEPROP 1 LAST WATTAGE 1/16W
J 0
(-1785 4350);
DISPLAY 0.638298 (-1785 4350);
FORCEPROP 1 LAST VALUE 4.7K
J 0
(-1780 4450);
DISPLAY 0.638298 (-1780 4450);
FORCEPROP 1 LAST MATERIAL CHIP
J 0
(-1785 4300);
DISPLAY 0.638298 (-1785 4300);
FORCEPROP 2 LAST CDS_LIB pure_quanta
J 0
(-1825 4375);
PAINT MONO (-1825 4375);
DISPLAY INVISIBLE (-1825 4375);
FORCEPROP 1 LAST PATH I53
J 0
(-1775 4550);
DISPLAY 0.978723 (-1775 4550);
PAINT WHITE (-1775 4550);
DISPLAY INVISIBLE (-1775 4550);
FORCEPROP 1 LAST PART_NUMBER CS24702JB10
J 0
(-1785 4200);
DISPLAY 0.638298 (-1785 4200);
DISPLAY INVISIBLE (-1785 4200);
FORCEADD UNIVERSAL_POWER..1
(-1825 4600);
FORCEPROP 3 LASTPIN (-1825 4550) SIG_NAME P3V3_AUX\g
J 0
(-1815 4560);
DISPLAY 0.659574 (-1815 4560);
PAINT MONO (-1815 4560);
DISPLAY INVISIBLE (-1815 4560);
FORCEPROP 1 LAST HDL_POWER P3V3_AUX
J 1
(-1825 4650);
DISPLAY 0.872340 (-1825 4650);
PAINT GREEN (-1825 4650);
FORCEPROP 2 LAST CDS_LIB pure_quanta_power
J 0
(-1825 4600);
PAINT MONO (-1825 4600);
DISPLAY INVISIBLE (-1825 4600);
FORCEPROP 1 LAST PATH I54
J 0
(-1775 4625);
DISPLAY 0.872340 (-1775 4625);
PAINT AQUA (-1775 4625);
DISPLAY INVISIBLE (-1775 4625);
FORCEADD Q_RES..2
(-775 3100);
FORCEPROP 1 LAST LOCATION R3438
J 0
(-730 3225);
DISPLAY 0.638298 (-730 3225);
FORCEPROP 2 LAST $SEC 1
J 0
(-725 3325);
DISPLAY 0.680851 (-725 3325);
PAINT MONO (-725 3325);
DISPLAY INVISIBLE (-725 3325);
FORCEPROP 2 LAST CDS_SEC 1
J 0
(-725 3325);
DISPLAY 1.021277 (-725 3325);
DISPLAY INVISIBLE (-725 3325);
FORCEPROP 1 LASTPIN (-775 3200) $PN 1
J 0
(-770 3162);
DISPLAY 0.787234 (-770 3162);
FORCEPROP 1 LASTPIN (-775 3000) $PN 2
J 0
(-770 3010);
DISPLAY 0.787234 (-770 3010);
FORCEPROP 1 LAST TOLERANCE 1%
J 0
(-730 3125);
DISPLAY 0.638298 (-730 3125);
FORCEPROP 1 LAST VALUE 100K
J 0
(-730 3175);
DISPLAY 0.638298 (-730 3175);
FORCEPROP 1 LAST MATERIAL CHIP
J 0
(-735 3025);
DISPLAY 0.638298 (-735 3025);
FORCEPROP 1 LAST PACK_TYPE 0402LF
J 0
(-735 2975);
DISPLAY 0.638298 (-735 2975);
FORCEPROP 1 LAST WATTAGE 1/16W
J 0
(-735 3075);
DISPLAY 0.638298 (-735 3075);
FORCEPROP 2 LAST CDS_LIB pure_quanta
J 0
(-775 3100);
PAINT MONO (-775 3100);
DISPLAY INVISIBLE (-775 3100);
FORCEPROP 1 LAST PATH I55
J 0
(-725 3275);
DISPLAY 0.978723 (-725 3275);
PAINT WHITE (-725 3275);
DISPLAY INVISIBLE (-725 3275);
FORCEPROP 1 LAST PART_NUMBER CS41002FB09
J 0
(-735 2925);
DISPLAY 0.638298 (-735 2925);
DISPLAY INVISIBLE (-735 2925);
FORCEADD UNIVERSAL_POWER..1
(-775 3325);
FORCEPROP 3 LASTPIN (-775 3275) SIG_NAME P3V3_AUX\g
J 0
(-765 3285);
DISPLAY 0.659574 (-765 3285);
PAINT MONO (-765 3285);
DISPLAY INVISIBLE (-765 3285);
FORCEPROP 1 LAST HDL_POWER P3V3_AUX
J 1
(-775 3375);
DISPLAY 0.872340 (-775 3375);
PAINT GREEN (-775 3375);
FORCEPROP 2 LAST CDS_LIB pure_quanta_power
J 0
(-775 3325);
PAINT MONO (-775 3325);
DISPLAY INVISIBLE (-775 3325);
FORCEPROP 1 LAST PATH I56
J 0
(-725 3350);
DISPLAY 0.872340 (-725 3350);
PAINT AQUA (-725 3350);
DISPLAY INVISIBLE (-725 3350);
FORCEADD MOSFET_NCH_DUAL..2
(-725 4075);
FORCEPROP 1 LAST LOCATION Q101
J 0
(-574 4051);
DISPLAY 0.723404 (-574 4051);
PAINT GREEN (-574 4051);
FORCEPROP 0 LAST $SEC 2
J 0
(-550 4200);
DISPLAY 0.680851 (-550 4200);
PAINT MONO (-550 4200);
DISPLAY INVISIBLE (-550 4200);
FORCEPROP 0 LAST CDS_SEC 2
J 0
(-550 4200);
DISPLAY 1.021277 (-550 4200);
DISPLAY INVISIBLE (-550 4200);
FORCEPROP 0 LASTPIN (-675 4275) $PN 3
R 1
J 0
(-685 4285);
DISPLAY 0.680851 (-685 4285);
PAINT MONO (-685 4285);
FORCEPROP 0 LASTPIN (-925 4025) $PN 5
J 2
(-935 4035);
DISPLAY 0.680851 (-935 4035);
PAINT MONO (-935 4035);
FORCEPROP 0 LASTPIN (-675 3875) $PN 4
R 1
J 2
(-685 3865);
DISPLAY 0.680851 (-685 3865);
PAINT MONO (-685 3865);
FORCEPROP 2 LAST VALUE PJT138K
J 0
(-550 4100);
DISPLAY 1.021277 (-550 4100);
FORCEPROP 2 LAST PART_TYPE SMLF
J 0
(-550 4150);
DISPLAY 1.021277 (-550 4150);
FORCEPROP 1 LAST MATERIAL IC
J 0
(-574 3926);
DISPLAY 0.723404 (-574 3926);
PAINT GREEN (-574 3926);
FORCEPROP 2 LAST CDS_LIB pure_quanta
J 0
(-725 4075);
DISPLAY INVISIBLE (-725 4075);
FORCEPROP 1 LAST NEEDS_NO_SIZE TRUE
J 0
(-575 3966);
DISPLAY 0.468085 (-575 3966);
PAINT GREEN (-575 3966);
DISPLAY INVISIBLE (-575 3966);
FORCEPROP 1 LAST CDS_LMAN_SYM_OUTLINE -150,150,150,-150
J 0
(-725 4075);
DISPLAY 0.468085 (-725 4075);
PAINT GREEN (-725 4075);
DISPLAY INVISIBLE (-725 4075);
FORCEPROP 1 LAST PATH I57
J 0
(-575 3925);
DISPLAY 0.723404 (-575 3925);
PAINT GREEN (-575 3925);
DISPLAY INVISIBLE (-575 3925);
FORCEPROP 1 LAST PART_NUMBER BAM138K0003
J 0
(-574 3981);
DISPLAY 0.723404 (-574 3981);
PAINT GREEN (-574 3981);
DISPLAY INVISIBLE (-574 3981);
FORCEADD UNIVERSAL_GND..1
(-675 3700);
FORCEPROP 3 LASTPIN (-675 3750) SIG_NAME GND\g
J 0
(-665 3760);
DISPLAY 0.659574 (-665 3760);
PAINT MONO (-665 3760);
DISPLAY INVISIBLE (-665 3760);
FORCEPROP 2 LAST CDS_LIB pure_quanta_power
J 0
(-675 3700);
DISPLAY INVISIBLE (-675 3700);
FORCEPROP 1 LAST HDL_POWER GND
J 1
(-650 3625);
DISPLAY 0.872340 (-650 3625);
PAINT GREEN (-650 3625);
DISPLAY INVISIBLE (-650 3625);
FORCEPROP 1 LAST PATH I58
J 0
(-600 3700);
DISPLAY 0.872340 (-600 3700);
PAINT AQUA (-600 3700);
DISPLAY INVISIBLE (-600 3700);
FORCEADD Q_RES..2
R 2
(-675 4500);
FORCEPROP 1 LAST LOCATION R3439
J 2
(-720 4625);
DISPLAY 0.638298 (-720 4625);
FORCEPROP 2 LAST $SEC 1
J 2
(-725 4725);
DISPLAY 0.680851 (-725 4725);
PAINT MONO (-725 4725);
DISPLAY INVISIBLE (-725 4725);
FORCEPROP 2 LAST CDS_SEC 1
J 2
(-725 4725);
DISPLAY 1.021277 (-725 4725);
DISPLAY INVISIBLE (-725 4725);
FORCEPROP 1 LASTPIN (-675 4600) $PN 1
J 2
(-680 4562);
DISPLAY 0.787234 (-680 4562);
FORCEPROP 1 LASTPIN (-675 4400) $PN 2
J 2
(-680 4410);
DISPLAY 0.787234 (-680 4410);
FORCEPROP 1 LAST PACK_TYPE 0402LF
J 2
(-715 4375);
DISPLAY 0.638298 (-715 4375);
FORCEPROP 1 LAST MATERIAL CHIP
J 2
(-715 4425);
DISPLAY 0.638298 (-715 4425);
FORCEPROP 1 LAST WATTAGE 1/16W
J 2
(-715 4475);
DISPLAY 0.638298 (-715 4475);
FORCEPROP 1 LAST VALUE 100K
J 2
(-720 4575);
DISPLAY 0.638298 (-720 4575);
FORCEPROP 1 LAST TOLERANCE 1%
J 2
(-720 4525);
DISPLAY 0.638298 (-720 4525);
FORCEPROP 2 LAST CDS_LIB pure_quanta
J 2
(-675 4500);
PAINT MONO (-675 4500);
DISPLAY INVISIBLE (-675 4500);
FORCEPROP 1 LAST PATH I59
J 2
(-725 4675);
DISPLAY 0.978723 (-725 4675);
PAINT WHITE (-725 4675);
DISPLAY INVISIBLE (-725 4675);
FORCEPROP 1 LAST PART_NUMBER CS41002FB09
J 2
(-715 4325);
DISPLAY 0.638298 (-715 4325);
DISPLAY INVISIBLE (-715 4325);
FORCEADD OFFPAGE..4
R 2
(-3175 975);
FORCEPROP 2 LAST $XR0 120 
J 0
(-3427 975);
DISPLAY 0.638298 (-3427 975);
PAINT MONO (-3427 975);
FORCEPROP 2 LAST CDS_LIB standard
J 0
(-3175 975);
DISPLAY INVISIBLE (-3175 975);
FORCEPROP 1 LAST OFFPAGE TRUE
J 2
(-3500 850);
DISPLAY 0.872340 (-3500 850);
PAINT GREEN (-3500 850);
DISPLAY INVISIBLE (-3500 850);
FORCEPROP 1 LAST COMMENT_BODY TRUE
J 2
(-3150 875);
DISPLAY 0.872340 (-3150 875);
PAINT GREEN (-3150 875);
DISPLAY INVISIBLE (-3150 875);
FORCEPROP 2 LAST PATH I6
J 0
(-3425 1025);
DISPLAY 1.021277 (-3425 1025);
DISPLAY INVISIBLE (-3425 1025);
FORCEADD UNIVERSAL_GND..1
(100 1100);
FORCEPROP 3 LASTPIN (100 1150) SIG_NAME GND\g
J 0
(110 1160);
DISPLAY 0.659574 (110 1160);
PAINT MONO (110 1160);
DISPLAY INVISIBLE (110 1160);
FORCEPROP 2 LAST CDS_LIB pure_quanta_power
J 0
(100 1100);
DISPLAY INVISIBLE (100 1100);
FORCEPROP 1 LAST HDL_POWER GND
J 1
(125 1025);
DISPLAY 0.872340 (125 1025);
PAINT GREEN (125 1025);
DISPLAY INVISIBLE (125 1025);
FORCEPROP 1 LAST PATH I60
J 0
(175 1100);
DISPLAY 0.872340 (175 1100);
PAINT AQUA (175 1100);
DISPLAY INVISIBLE (175 1100);
FORCEADD UNIVERSAL_GND..1
(50 2450);
FORCEPROP 3 LASTPIN (50 2500) SIG_NAME GND\g
J 0
(60 2510);
DISPLAY 0.659574 (60 2510);
PAINT MONO (60 2510);
DISPLAY INVISIBLE (60 2510);
FORCEPROP 2 LAST CDS_LIB pure_quanta_power
J 0
(50 2450);
DISPLAY INVISIBLE (50 2450);
FORCEPROP 1 LAST HDL_POWER GND
J 1
(75 2375);
DISPLAY 0.872340 (75 2375);
PAINT GREEN (75 2375);
DISPLAY INVISIBLE (75 2375);
FORCEPROP 1 LAST PATH I61
J 0
(125 2450);
DISPLAY 0.872340 (125 2450);
PAINT AQUA (125 2450);
DISPLAY INVISIBLE (125 2450);
FORCEADD OFFPAGE..2
(350 1550);
FORCEPROP 2 LAST $XR0 81 
J 0
(539 1550);
DISPLAY 0.638298 (539 1550);
PAINT MONO (539 1550);
FORCEPROP 2 LAST CDS_LIB standard
J 0
(350 1550);
DISPLAY INVISIBLE (350 1550);
FORCEPROP 1 LAST OFFPAGE TRUE
J 0
(675 1425);
DISPLAY 0.872340 (675 1425);
PAINT AQUA (675 1425);
DISPLAY INVISIBLE (675 1425);
FORCEPROP 1 LAST COMMENT_BODY TRUE
J 0
(305 1455);
DISPLAY 0.872340 (305 1455);
PAINT GREEN (305 1455);
DISPLAY INVISIBLE (305 1455);
FORCEPROP 2 LAST PATH I62
J 0
(550 1600);
DISPLAY 1.021277 (550 1600);
DISPLAY INVISIBLE (550 1600);
FORCEADD UNIVERSAL_GND..1
(-2900 600);
FORCEPROP 3 LASTPIN (-2900 650) SIG_NAME GND\g
J 0
(-2890 660);
DISPLAY 0.659574 (-2890 660);
PAINT MONO (-2890 660);
DISPLAY INVISIBLE (-2890 660);
FORCEPROP 2 LAST CDS_LIB pure_quanta_power
J 0
(-2900 600);
DISPLAY INVISIBLE (-2900 600);
FORCEPROP 1 LAST HDL_POWER GND
J 1
(-2875 525);
DISPLAY 0.872340 (-2875 525);
PAINT GREEN (-2875 525);
DISPLAY INVISIBLE (-2875 525);
FORCEPROP 1 LAST PATH I7
J 0
(-2825 600);
DISPLAY 0.872340 (-2825 600);
PAINT AQUA (-2825 600);
DISPLAY INVISIBLE (-2825 600);
FORCEADD Q_CAP..1
(50 2650);
FORCEPROP 1 LAST LOCATION C1973
J 0
(100 2750);
DISPLAY 0.978723 (100 2750);
FORCEPROP 0 LAST $SEC 1
J 0
(100 2800);
DISPLAY 0.680851 (100 2800);
PAINT MONO (100 2800);
DISPLAY INVISIBLE (100 2800);
FORCEPROP 0 LAST CDS_SEC 1
J 0
(100 2800);
DISPLAY 1.021277 (100 2800);
DISPLAY INVISIBLE (100 2800);
FORCEPROP 1 LASTPIN (50 2750) $PN 1
J 0
(60 2730);
DISPLAY 0.787234 (60 2730);
PAINT MONO (60 2730);
FORCEPROP 1 LASTPIN (50 2550) $PN 2
J 0
(60 2530);
DISPLAY 0.787234 (60 2530);
PAINT MONO (60 2530);
FORCEPROP 1 LAST VALUE 0.1UF
J 0
(100 2700);
DISPLAY 0.638298 (100 2700);
FORCEPROP 1 LAST VOLTAGE 25V
J 0
(100 2650);
DISPLAY 0.638298 (100 2650);
FORCEPROP 1 LAST TOLERANCE 10%
J 0
(100 2600);
DISPLAY 0.638298 (100 2600);
FORCEPROP 1 LAST MATERIAL X7R
J 0
(100 2550);
DISPLAY 0.638298 (100 2550);
PAINT RED (100 2550);
FORCEPROP 1 LAST PACK_TYPE 0402
J 0
(100 2450);
DISPLAY 0.638298 (100 2450);
FORCEPROP 2 LAST CDS_LIB pure_quanta
J 0
(50 2650);
DISPLAY INVISIBLE (50 2650);
FORCEPROP 1 LAST PATH I71
J 0
(100 2800);
DISPLAY 0.978723 (100 2800);
PAINT WHITE (100 2800);
DISPLAY INVISIBLE (100 2800);
FORCEPROP 1 LAST PART_NUMBER CH4104K1B00
J 0
(100 2500);
DISPLAY 0.638298 (100 2500);
DISPLAY INVISIBLE (100 2500);
FORCEADD OFFPAGE..2
(250 2900);
FORCEPROP 2 LAST $XR0 81 
J 0
(439 2900);
DISPLAY 0.638298 (439 2900);
PAINT MONO (439 2900);
FORCEPROP 2 LAST CDS_LIB standard
J 0
(250 2900);
DISPLAY INVISIBLE (250 2900);
FORCEPROP 1 LAST OFFPAGE TRUE
J 0
(575 2775);
DISPLAY 0.872340 (575 2775);
PAINT AQUA (575 2775);
DISPLAY INVISIBLE (575 2775);
FORCEPROP 1 LAST COMMENT_BODY TRUE
J 0
(205 2805);
DISPLAY 0.872340 (205 2805);
PAINT GREEN (205 2805);
DISPLAY INVISIBLE (205 2805);
FORCEPROP 2 LAST PATH I72
J 0
(450 2950);
DISPLAY 1.021277 (450 2950);
DISPLAY INVISIBLE (450 2950);
FORCEADD UNIVERSAL_GND..1
(100 3825);
FORCEPROP 3 LASTPIN (100 3875) SIG_NAME GND\g
J 0
(110 3885);
DISPLAY 0.659574 (110 3885);
PAINT MONO (110 3885);
DISPLAY INVISIBLE (110 3885);
FORCEPROP 2 LAST CDS_LIB pure_quanta_power
J 0
(100 3825);
DISPLAY INVISIBLE (100 3825);
FORCEPROP 1 LAST HDL_POWER GND
J 1
(125 3750);
DISPLAY 0.872340 (125 3750);
PAINT GREEN (125 3750);
DISPLAY INVISIBLE (125 3750);
FORCEPROP 1 LAST PATH I73
J 0
(175 3825);
DISPLAY 0.872340 (175 3825);
PAINT AQUA (175 3825);
DISPLAY INVISIBLE (175 3825);
FORCEADD Q_CAP..1
(100 4025);
FORCEPROP 1 LAST LOCATION C1974
J 0
(150 4125);
DISPLAY 0.978723 (150 4125);
FORCEPROP 0 LAST $SEC 1
J 0
(150 4175);
DISPLAY 0.680851 (150 4175);
PAINT MONO (150 4175);
DISPLAY INVISIBLE (150 4175);
FORCEPROP 0 LAST CDS_SEC 1
J 0
(150 4175);
DISPLAY 1.021277 (150 4175);
DISPLAY INVISIBLE (150 4175);
FORCEPROP 1 LASTPIN (100 4125) $PN 1
J 0
(110 4105);
DISPLAY 0.787234 (110 4105);
PAINT MONO (110 4105);
FORCEPROP 1 LASTPIN (100 3925) $PN 2
J 0
(110 3905);
DISPLAY 0.787234 (110 3905);
PAINT MONO (110 3905);
FORCEPROP 1 LAST VOLTAGE 25V
J 0
(150 4025);
DISPLAY 0.638298 (150 4025);
FORCEPROP 1 LAST PACK_TYPE 0402
J 0
(150 3825);
DISPLAY 0.638298 (150 3825);
FORCEPROP 1 LAST MATERIAL X7R
J 0
(150 3925);
DISPLAY 0.638298 (150 3925);
PAINT RED (150 3925);
FORCEPROP 1 LAST TOLERANCE 10%
J 0
(150 3975);
DISPLAY 0.638298 (150 3975);
FORCEPROP 1 LAST VALUE 0.1UF
J 0
(150 4075);
DISPLAY 0.638298 (150 4075);
FORCEPROP 2 LAST CDS_LIB pure_quanta
J 0
(100 4025);
DISPLAY INVISIBLE (100 4025);
FORCEPROP 1 LAST PATH I74
J 0
(150 4175);
DISPLAY 0.978723 (150 4175);
PAINT WHITE (150 4175);
DISPLAY INVISIBLE (150 4175);
FORCEPROP 1 LAST PART_NUMBER CH4104K1B00
J 0
(150 3875);
DISPLAY 0.638298 (150 3875);
DISPLAY INVISIBLE (150 3875);
FORCEADD OFFPAGE..2
(450 4325);
FORCEPROP 2 LAST $XR0 81 
J 0
(639 4325);
DISPLAY 0.638298 (639 4325);
PAINT MONO (639 4325);
FORCEPROP 2 LAST CDS_LIB standard
J 0
(450 4325);
DISPLAY INVISIBLE (450 4325);
FORCEPROP 1 LAST OFFPAGE TRUE
J 0
(775 4200);
DISPLAY 0.872340 (775 4200);
PAINT AQUA (775 4200);
DISPLAY INVISIBLE (775 4200);
FORCEPROP 1 LAST COMMENT_BODY TRUE
J 0
(405 4230);
DISPLAY 0.872340 (405 4230);
PAINT GREEN (405 4230);
DISPLAY INVISIBLE (405 4230);
FORCEPROP 2 LAST PATH I75
J 0
(650 4375);
DISPLAY 1.021277 (650 4375);
DISPLAY INVISIBLE (650 4375);
FORCEADD UNIVERSAL_POWER..1
(-675 4725);
FORCEPROP 3 LASTPIN (-675 4675) SIG_NAME P3V3_AUX\g
J 0
(-665 4685);
DISPLAY 0.659574 (-665 4685);
PAINT MONO (-665 4685);
DISPLAY INVISIBLE (-665 4685);
FORCEPROP 1 LAST HDL_POWER P3V3_AUX
J 1
(-675 4775);
DISPLAY 0.872340 (-675 4775);
PAINT GREEN (-675 4775);
FORCEPROP 2 LAST CDS_LIB pure_quanta_power
J 0
(-675 4725);
PAINT MONO (-675 4725);
DISPLAY INVISIBLE (-675 4725);
FORCEPROP 1 LAST PATH I83
J 0
(-625 4750);
DISPLAY 0.872340 (-625 4750);
PAINT AQUA (-625 4750);
DISPLAY INVISIBLE (-625 4750);
FORCEADD DNS..2
(1600 3025);
PAINT RED (1600 3025);
FORCEPROP 2 LAST CDS_LIB mstr_misc
J 0
(1600 3025);
DISPLAY INVISIBLE (1600 3025);
FORCEPROP 1 LAST COMMENT_BODY TRUE
J 0
(1600 3025);
DISPLAY INVISIBLE (1600 3025);
FORCEADD DESIGN_NOTE..1
(3050 4775);
FORCEPROP 0 LAST L1 LEAVE GPU_WP_HW_CTRL_ISO_N FLOATING PER NV DESIGN GUIDE REQUIREMENT
J 0
(2850 4650);
DISPLAY 0.808511 (2850 4650);
PAINT SKYBLUE (2850 4650);
FORCEPROP 2 LAST CDS_LIB pure_quanta_power
J 0
(3050 4775);
DISPLAY INVISIBLE (3050 4775);
FORCEPROP 0 LAST L2 UART_2 BMC TO MB (BMC HOST)
J 0
(2850 4575);
DISPLAY 0.808511 (2850 4575);
PAINT SKYBLUE (2850 4575);
DISPLAY INVISIBLE (2850 4575);
FORCEPROP 1 LAST COMMENT_BODY TRUE
J 0
(3075 4875);
DISPLAY 0.978723 (3075 4875);
DISPLAY INVISIBLE (3075 4875);
FORCEADD DNS..2
(3725 4150);
PAINT RED (3725 4150);
FORCEPROP 2 LAST CDS_LIB mstr_misc
J 0
(3725 4150);
DISPLAY INVISIBLE (3725 4150);
FORCEPROP 1 LAST COMMENT_BODY TRUE
J 0
(3725 4150);
DISPLAY INVISIBLE (3725 4150);
FORCEADD DNS..2
(4600 3650);
PAINT RED (4600 3650);
FORCEPROP 2 LAST CDS_LIB mstr_misc
J 0
(4600 3650);
DISPLAY INVISIBLE (4600 3650);
FORCEPROP 1 LAST COMMENT_BODY TRUE
J 0
(4600 3650);
DISPLAY INVISIBLE (4600 3650);
FORCEADD DNS..2
(1725 1175);
PAINT RED (1725 1175);
FORCEPROP 2 LAST CDS_LIB mstr_misc
J 0
(1725 1175);
DISPLAY INVISIBLE (1725 1175);
FORCEPROP 1 LAST COMMENT_BODY TRUE
J 0
(1725 1175);
DISPLAY INVISIBLE (1725 1175);
FORCEADD DNS..2
(1750 -550);
PAINT RED (1750 -550);
FORCEPROP 2 LAST CDS_LIB mstr_misc
J 0
(1750 -550);
DISPLAY INVISIBLE (1750 -550);
FORCEPROP 1 LAST COMMENT_BODY TRUE
J 0
(1750 -550);
DISPLAY INVISIBLE (1750 -550);
FORCEADD QUANTA_TITLE_BLOCK_C..1
(5475 -1450);
FORCEPROP 0 LAST CDS_CON_LAST_MODIFIED Thu Sep 14 16:12:23 2023
J 0
(3590 -1435);
PAINT MONO (3590 -1435);
DISPLAY INVISIBLE (3590 -1435);
FORCEPROP 2 LAST CUSTOM_TXT_CDS <XR_PAGE_TITLE>
J 0
(-2415 3800);
DISPLAY 0.638298 (-2415 3800);
PAINT PINK (-2415 3800);
DISPLAY INVISIBLE (-2415 3800);
FORCEPROP 2 LAST CUSTOM_TXT_CDS <CON_LAST_MODIFIED>
J 0
(3590 -1435);
DISPLAY 0.978723 (3590 -1435);
FORCEPROP 2 LAST CUSTOM_TXT_CDS <NAME_1>
J 0
(2300 -1275);
FORCEPROP 2 LAST CUSTOM_TXT_CDS <NAME_2>
J 0
(2300 -1400);
FORCEPROP 2 LAST CUSTOM_TXT_CDS <Q_PROJ>
J 0
(3093 -1348);
DISPLAY 1.212766 (3093 -1348);
FORCEPROP 2 LAST CUSTOM_TXT_CDS <Q_NUMBER>
J 0
(4072 -1347);
DISPLAY 1.212766 (4072 -1347);
FORCEPROP 2 LAST CUSTOM_TXT_CDS <CON_PAGE_NUM> OF <CON_TOTAL_PAGES>
J 0
(5029 -1432);
DISPLAY 0.978723 (5029 -1432);
FORCEPROP 2 LAST CUSTOM_TXT_CDS <Q_REV>
J 0
(5291 -1347);
DISPLAY 1.212766 (5291 -1347);
FORCEPROP 1 LAST Q_TITLE EXAMAX_ISO (3/7)
J 0
(-3775 -1400);
DISPLAY 2.446809 (-3775 -1400);
PAINT GREEN (-3775 -1400);
FORCEPROP 2 LAST PAGE_BORDER TRUE
J 0
(-2415 3800);
DISPLAY 0.638298 (-2415 3800);
PAINT PINK (-2415 3800);
DISPLAY INVISIBLE (-2415 3800);
FORCEPROP 1 LAST CDS_LMAN_SYM_OUTLINE -9475,6775,100,-125
J 0
(5475 -1450);
DISPLAY 0.468085 (5475 -1450);
PAINT GREEN (5475 -1450);
DISPLAY INVISIBLE (5475 -1450);
FORCEPROP 2 LAST CDS_LIB pure_quanta
J 0
(5475 -1450);
PAINT MONO (5475 -1450);
DISPLAY INVISIBLE (5475 -1450);
FORCEPROP 2 LAST CDS_XR_PAGE_TITLE CR-126 : @T6G_MB_LIB.T6G(SCH_1):PAGE126
J 0
(-2415 3800);
DISPLAY 0.638298 (-2415 3800);
PAINT PINK (-2415 3800);
DISPLAY INVISIBLE (-2415 3800);
FORCEPROP 1 LAST Q_DEPT BU9
J 1
(1712 -1401);
DISPLAY 1.957447 (1712 -1401);
PAINT GREEN (1712 -1401);
DISPLAY INVISIBLE (1712 -1401);
FORCEPROP 1 LAST COMMENT_BODY TRUE
J 0
(5487 -1463);
DISPLAY 0.978723 (5487 -1463);
PAINT GREEN (5487 -1463);
DISPLAY INVISIBLE (5487 -1463);
FORCEADD DNS..2
(-2975 2575);
PAINT RED (-2975 2575);
FORCEPROP 2 LAST CDS_LIB mstr_misc
J 0
(-2975 2575);
DISPLAY INVISIBLE (-2975 2575);
FORCEPROP 1 LAST COMMENT_BODY TRUE
J 0
(-2975 2575);
DISPLAY INVISIBLE (-2975 2575);
FORCEADD DNS..2
(-2975 3500);
PAINT RED (-2975 3500);
FORCEPROP 2 LAST CDS_LIB mstr_misc
J 0
(-2975 3500);
DISPLAY INVISIBLE (-2975 3500);
FORCEPROP 1 LAST COMMENT_BODY TRUE
J 0
(-2975 3500);
DISPLAY INVISIBLE (-2975 3500);
FORCEADD DNS..2
(-2900 750);
PAINT RED (-2900 750);
FORCEPROP 2 LAST CDS_LIB mstr_misc
J 0
(-2900 750);
DISPLAY INVISIBLE (-2900 750);
FORCEPROP 1 LAST COMMENT_BODY TRUE
J 0
(-2900 750);
DISPLAY INVISIBLE (-2900 750);
FORCEADD DNS..2
(-2950 -825);
PAINT RED (-2950 -825);
FORCEPROP 2 LAST CDS_LIB mstr_misc
J 0
(-2950 -825);
DISPLAY INVISIBLE (-2950 -825);
FORCEPROP 1 LAST COMMENT_BODY TRUE
J 0
(-2950 -825);
DISPLAY INVISIBLE (-2950 -825);
WIRE 16 -1 (-2925 1450)(-2925 1350);
WIRE 16 -1 (-2950 2000)(-2950 2025);
WIRE 16 -1 (-2975 2800)(-2975 2700);
WIRE 16 -1 (3875 2425)(3875 2275);
WIRE 16 -1 (4775 1450)(4775 1400);
WIRE 16 -1 (2950 2175)(2950 2025);
WIRE 16 -1 (3875 1525)(3875 1400);
WIRE 16 -1 (2950 1250)(2950 1125);
WIRE 16 -1 (-2975 3375)(-2975 3425);
WIRE 16 -1 (1700 1875)(1700 1725);
WIRE 16 -1 (1725 1050)(1725 1100);
WIRE 16 -1 (4800 -275)(4800 -325);
WIRE 16 -1 (3900 700)(3900 550);
WIRE 16 -1 (3900 -200)(3900 -325);
WIRE 16 -1 (2975 450)(2975 300);
WIRE 16 -1 (2975 -475)(2975 -600);
WIRE 16 -1 (1725 150)(1725 0);
WIRE 16 -1 (1750 -675)(1750 -625);
WIRE 16 -1 (1600 2950)(1600 2825);
WIRE 16 -1 (1575 3800)(1575 3700);
WIRE 16 -1 (2750 3175)(2750 3050);
WIRE 16 -1 (2750 4125)(2750 3975);
WIRE 16 -1 (3725 3475)(3725 3350);
WIRE 16 -1 (3725 4425)(3725 4275);
WIRE 16 -1 (4600 3575)(4600 3450);
WIRE 16 -1 (-2950 -950)(-2950 -900);
WIRE 16 -1 (-3000 4200)(-3000 4100);
WIRE 16 -1 (-1725 -750)(-1725 -875);
WIRE 16 -1 (-1725 175)(-1725 25);
WIRE 16 -1 (-800 -475)(-800 -600);
WIRE 16 -1 (-800 425)(-800 275);
WIRE 16 -1 (100 -550)(100 -600);
WIRE 16 -1 (-1750 825)(-1750 700);
WIRE 16 -1 (-1750 1725)(-1750 1575);
WIRE 16 -1 (-1750 2175)(-1750 2050);
WIRE 16 -1 (-800 1100)(-800 975);
WIRE 16 -1 (-800 1975)(-800 1825);
WIRE 16 -1 (-775 2475)(-775 2350);
WIRE 16 -1 (-2975 -125)(-2975 -275);
WIRE 16 -1 (-1775 3075)(-1775 2925);
WIRE 16 -1 (-1825 3575)(-1825 3450);
WIRE 16 -1 (-1825 4550)(-1825 4475);
WIRE 16 -1 (-775 3275)(-775 3200);
WIRE 16 -1 (-675 3875)(-675 3750);
WIRE 16 -1 (100 1200)(100 1150);
WIRE 16 -1 (50 2550)(50 2500);
WIRE 16 -1 (-2900 650)(-2900 675);
WIRE 16 -1 (100 3925)(100 3875);
WIRE 16 -1 (-675 4675)(-675 4600);
WIRE 16 -1 (2500 3325)(1600 3325);
FORCEPROP 2 LAST SIG_NAME GPU_WP_HW_CTRL_N
J 0
(1640 3335);
DISPLAY 0.808511 (1640 3335);
WIRE 16 -1 (1600 3325)(1575 3325);
WIRE 16 -1 (1600 3325)(1600 3150);
WIRE 16 -1 (1575 3500)(1575 3325);
WIRE 16 -1 (1575 3325)(1375 3325);
WIRE 16 -1 (-2925 1150)(-2925 975);
WIRE 16 -1 (-2900 975)(-2925 975);
WIRE 16 -1 (-2925 975)(-3125 975);
WIRE 16 -1 (-2000 975)(-2900 975);
FORCEPROP 2 LAST SIG_NAME GPU_HMC_PRSNT_N
J 0
(-2735 985);
DISPLAY 0.808511 (-2735 985);
WIRE 16 -1 (-2900 875)(-2900 975);
WIRE 16 -1 (-1050 1250)(-1750 1250);
FORCEPROP 2 LAST SIG_NAME GPU_HMC_PRSNT
J 0
(-1710 1260);
DISPLAY 0.808511 (-1710 1260);
FORCEPROP 2 LASTPROP $XRERR UNIQUE?
J 0
(-1950 1260);
DISPLAY 0.638298 (-1950 1260);
PAINT MONO (-1950 1260);
DISPLAY INVISIBLE (-1950 1260);
WIRE 16 -1 (-1750 1375)(-1750 1250);
WIRE 16 -1 (-1750 1250)(-1750 1225);
WIRE 16 -1 (-2975 2500)(-2975 2325);
WIRE 16 -1 (-2950 2325)(-2975 2325);
WIRE 16 -1 (-2975 2325)(-3125 2325);
WIRE 16 -1 (-2000 2325)(-2950 2325);
FORCEPROP 2 LAST SIG_NAME GPU_BASE_HMC_READY
J 0
(-2910 2335);
DISPLAY 0.808511 (-2910 2335);
WIRE 16 -1 (-2950 2225)(-2950 2325);
WIRE 16 -1 (-1775 2725)(-1775 2625);
WIRE 16 -1 (-1750 2625)(-1775 2625);
WIRE 16 -1 (-1025 2625)(-1750 2625);
FORCEPROP 2 LAST SIG_NAME GPU_BASE_HMC_READY_N
J 0
(-1735 2635);
DISPLAY 0.808511 (-1735 2635);
FORCEPROP 2 LASTPROP $XRERR UNIQUE?
J 0
(-1975 2635);
DISPLAY 0.638298 (-1975 2635);
PAINT MONO (-1975 2635);
DISPLAY INVISIBLE (-1975 2635);
WIRE 16 -1 (-1750 2625)(-1750 2575);
WIRE 16 -1 (-2975 -475)(-2975 -600);
WIRE 16 -1 (-2950 -600)(-2975 -600);
WIRE 16 -1 (-2975 -600)(-3200 -600);
WIRE 16 -1 (-1975 -600)(-2950 -600);
FORCEPROP 2 LAST SIG_NAME GPU_FPGA_OVERT_N
J 0
(-2810 -590);
DISPLAY 0.808511 (-2810 -590);
WIRE 16 -1 (-2950 -700)(-2950 -600);
WIRE 16 -1 (-925 4025)(-1825 4025);
FORCEPROP 2 LAST SIG_NAME GPU_FPGA_THERM_OVERT
J 0
(-1760 4035);
DISPLAY 0.808511 (-1760 4035);
FORCEPROP 2 LASTPROP $XRERR UNIQUE?
J 0
(-2000 4035);
DISPLAY 0.638298 (-2000 4035);
PAINT MONO (-2000 4035);
DISPLAY INVISIBLE (-2000 4035);
WIRE 16 -1 (-1825 4275)(-1825 4025);
WIRE 16 -1 (-1825 3975)(-1825 4025);
WIRE 16 -1 (-3000 3900)(-3000 3725);
WIRE 16 -1 (-2975 3725)(-3000 3725);
WIRE 16 -1 (-3000 3725)(-3200 3725);
WIRE 16 -1 (-2075 3725)(-2975 3725);
FORCEPROP 2 LAST SIG_NAME GPU_FPGA_THERM_OVERT_N
J 0
(-2935 3735);
DISPLAY 0.808511 (-2935 3735);
WIRE 16 -1 (-2975 3625)(-2975 3725);
WIRE 16 -1 (-1725 -175)(-1725 -325);
WIRE 16 -1 (-1050 -325)(-1725 -325);
FORCEPROP 2 LAST SIG_NAME GPU_FPGA_OVERT
J 0
(-1710 -315);
DISPLAY 0.808511 (-1710 -315);
FORCEPROP 2 LASTPROP $XRERR UNIQUE?
J 0
(-1950 -315);
DISPLAY 0.638298 (-1950 -315);
PAINT MONO (-1950 -315);
DISPLAY INVISIBLE (-1950 -315);
WIRE 16 -1 (-1725 -350)(-1725 -325);
WIRE 16 -1 (325 -50)(100 -50);
WIRE 16 -1 (100 -50)(100 -350);
WIRE 16 -1 (100 -50)(-800 -50);
FORCEPROP 2 LAST SIG_NAME GPU_FPGA_OVERT_ISO_N
J 0
(-710 -40);
DISPLAY 0.808511 (-710 -40);
WIRE 16 -1 (-800 75)(-800 -50);
WIRE 16 -1 (-800 -50)(-800 -75);
WIRE 16 -1 (-775 3000)(-775 2900);
WIRE 16 -1 (50 2900)(-775 2900);
FORCEPROP 2 LAST SIG_NAME GPU_BASE_HMC_READY_ISO
J 0
(-685 2910);
DISPLAY 0.808511 (-685 2910);
WIRE 16 -1 (-775 2875)(-775 2900);
WIRE 16 -1 (200 2900)(50 2900);
WIRE 16 -1 (50 2900)(50 2750);
WIRE 16 -1 (400 4325)(100 4325);
WIRE 16 -1 (100 4125)(100 4325);
WIRE 16 -1 (100 4325)(-675 4325);
FORCEPROP 2 LAST SIG_NAME GPU_FPGA_THERM_OVERT_ISO_N
J 0
(-610 4335);
DISPLAY 0.808511 (-610 4335);
WIRE 16 -1 (-675 4400)(-675 4325);
WIRE 16 -1 (-675 4325)(-675 4275);
WIRE 16 -1 (-800 1500)(-800 1550);
WIRE 16 -1 (100 1550)(-800 1550);
FORCEPROP 2 LAST SIG_NAME GPU_HMC_PRSNT_ISO_N
J 0
(-660 1560);
DISPLAY 0.808511 (-660 1560);
WIRE 16 -1 (-800 1625)(-800 1550);
WIRE 16 -1 (300 1550)(100 1550);
WIRE 16 -1 (100 1550)(100 1400);
WIRE 16 -1 (5025 225)(4800 225);
WIRE 16 -1 (4800 225)(3900 225);
FORCEPROP 2 LAST SIG_NAME GPU_FPGA_EROT_FATALERR_ISO_N
J 0
(3990 235);
DISPLAY 0.808511 (3990 235);
WIRE 16 -1 (4800 225)(4800 -75);
WIRE 16 -1 (3900 350)(3900 225);
WIRE 16 -1 (3900 225)(3900 200);
WIRE 16 -1 (1725 -200)(1725 -325);
WIRE 16 -1 (1750 -325)(1725 -325);
FORCEPROP 2 LAST SIG_NAME GPU_FPGA_EROT_FATALERR_N
J 0
(1740 -315);
DISPLAY 0.808511 (1740 -315);
WIRE 16 -1 (1725 -325)(1500 -325);
WIRE 16 -1 (2725 -325)(1750 -325);
WIRE 16 -1 (1750 -425)(1750 -325);
WIRE 16 -1 (2975 -75)(2975 -50);
WIRE 16 -1 (2975 100)(2975 -50);
WIRE 16 -1 (3650 -50)(2975 -50);
FORCEPROP 2 LAST SIG_NAME GPU_FPGA_EROT_FATALERR
J 0
(2990 -40);
DISPLAY 0.808511 (2990 -40);
FORCEPROP 2 LASTPROP $XRERR UNIQUE?
J 0
(2750 -40);
DISPLAY 0.638298 (2750 -40);
PAINT MONO (2750 -40);
DISPLAY INVISIBLE (2750 -40);
WIRE 16 -1 (5000 1950)(4775 1950);
WIRE 16 -1 (4775 1950)(4775 1650);
WIRE 16 -1 (4775 1950)(3875 1950);
FORCEPROP 2 LAST SIG_NAME GPU_PRSNT_N_ISO
J 0
(3965 1960);
DISPLAY 0.808511 (3965 1960);
WIRE 16 -1 (3875 2075)(3875 1950);
WIRE 16 -1 (3875 1950)(3875 1925);
WIRE 16 -1 (2950 1650)(2950 1675);
WIRE 16 -1 (3325 1675)(2950 1675);
FORCEPROP 2 LAST SIG_NAME GPU_PRSNT
J 0
(2965 1685);
DISPLAY 0.808511 (2965 1685);
WIRE 16 -1 (2950 1825)(2950 1675);
WIRE 16 -1 (3625 1675)(3325 1675);
WIRE 16 -1 (3325 1675)(3325 1950);
WIRE 16 -1 (3325 1950)(3425 1950);
WIRE 16 -1 (1700 1525)(1700 1400);
WIRE 16 -1 (1725 1400)(1700 1400);
WIRE 16 -1 (1700 1400)(1475 1400);
WIRE 16 -1 (2700 1400)(1725 1400);
FORCEPROP 2 LAST SIG_NAME GPU_PRSNT_N
J 0
(1865 1410);
DISPLAY 0.808511 (1865 1410);
WIRE 16 -1 (1725 1300)(1725 1400);
WIRE 16 -1 (4600 3775)(4600 3975);
WIRE 16 -1 (4600 3975)(4750 3975);
WIRE 16 -1 (3725 3975)(4600 3975);
WIRE 16 -1 (3725 4075)(3725 3975);
FORCEPROP 0 LAST SIG_NAME GPU_WP_HW_CTRL_ISO_N
J 0
(3990 3985);
DISPLAY 0.808511 (3990 3985);
WIRE 16 -1 (3725 3875)(3725 3975);
WIRE 16 -1 (2750 3775)(2750 3625);
WIRE 16 -1 (2750 3625)(3475 3625);
FORCEPROP 2 LAST SIG_NAME GPU_WP_HW_CTRL_ISO
J 0
(2815 3635);
DISPLAY 0.638298 (2815 3635);
FORCEPROP 2 LASTPROP $XRERR UNIQUE?
J 0
(2575 3635);
DISPLAY 0.638298 (2575 3635);
PAINT MONO (2575 3635);
DISPLAY INVISIBLE (2575 3635);
WIRE 16 -1 (2750 3575)(2750 3625);
DOT 1 (100 -50);
DOT 1 (-800 -50);
DOT 1 (-1725 -325);
DOT 1 (-775 2900);
DOT 1 (100 4325);
DOT 1 (-675 4325);
DOT 1 (-2925 975);
DOT 1 (-1750 1250);
DOT 1 (-800 1550);
DOT 1 (100 1550);
DOT 1 (50 2900);
DOT 1 (-1750 2625);
DOT 1 (-3000 3725);
DOT 1 (-1825 4025);
DOT 1 (-2975 3725);
DOT 1 (-2950 2325);
DOT 1 (-2900 975);
DOT 1 (-2950 -600);
DOT 1 (-2975 -600);
DOT 1 (-2975 2325);
DOT 1 (4800 225);
DOT 1 (3900 225);
DOT 1 (2975 -50);
DOT 1 (1725 -325);
DOT 1 (1750 -325);
DOT 1 (4775 1950);
DOT 1 (3875 1950);
DOT 1 (3325 1675);
DOT 1 (2950 1675);
DOT 1 (1700 1400);
DOT 1 (1725 1400);
DOT 1 (4600 3975);
DOT 1 (3725 3975);
DOT 1 (2750 3625);
DOT 1 (1600 3325);
DOT 1 (1575 3325);
QUIT
